FILE_TYPE = MACRO_DRAWING;
SET COLOR_WIRE YELLOW;
SET COLOR_PROP MONO;
SET COLOR_DOT WHITE;
SET COLOR_ARC YELLOW;
SET COLOR_BODY GREEN;
SET COLOR_NOTE MONO;
SET PROP_DISPLAY VALUE;
SET PAGE_NUMBER P53;
FORCEADD OFFPAGE..3
(1550 5250);
FORCEPROP 2 LAST $XR0 28 
J 0
(1764 5250);
DISPLAY 0.638298 (1764 5250);
PAINT MONO (1764 5250);
FORCEPROP 2 LAST $XR1 54 
J 0
(1854 5250);
DISPLAY 0.638298 (1854 5250);
PAINT MONO (1854 5250);
FORCEPROP 2 LAST CDS_LIB mstr_standard
J 0
(1550 5250);
DISPLAY 0.787234 (1550 5250);
PAINT MONO (1550 5250);
DISPLAY INVISIBLE (1550 5250);
FORCEPROP 1 LAST OFFPAGE TRUE
J 0
(1875 5125);
DISPLAY 0.936170 (1875 5125);
PAINT GREEN (1875 5125);
DISPLAY INVISIBLE (1875 5125);
FORCEPROP 1 LAST COMMENT_BODY TRUE
J 0
(1500 5150);
DISPLAY 0.936170 (1500 5150);
PAINT GREEN (1500 5150);
DISPLAY INVISIBLE (1500 5150);
FORCEPROP 2 LAST PATH I1
J 0
(1750 5325);
DISPLAY 0.787234 (1750 5325);
PAINT MONO (1750 5325);
DISPLAY INVISIBLE (1750 5325);
FORCEADD TAP..6
R 2
(650 5100);
FORCEPROP 3 LASTPIN (600 5100) SIG_NAME M_F_DQS_DP<16>
J 0
(610 5110);
DISPLAY 0.659574 (610 5110);
PAINT MONO (610 5110);
DISPLAY INVISIBLE (610 5110);
FORCEPROP 1 LASTPIN (600 5100) BN 16
J 2
(650 5110);
DISPLAY 0.617021 (650 5110);
PAINT PINK (650 5110);
FORCEPROP 2 LAST CDS_LIB mstr_standard
J 0
(650 5100);
DISPLAY 0.787234 (650 5100);
PAINT MONO (650 5100);
DISPLAY INVISIBLE (650 5100);
FORCEPROP 1 LAST BODY_TYPE PLUMBING
J 2
(650 5050);
DISPLAY 1.234043 (650 5050);
PAINT GREEN (650 5050);
DISPLAY INVISIBLE (650 5050);
FORCEPROP 1 LAST HDL_TAP TRUE
J 2
(325 4975);
DISPLAY 1.234043 (325 4975);
PAINT GREEN (325 4975);
DISPLAY INVISIBLE (325 4975);
FORCEPROP 1 LAST PATH I10
J 2
(650 5100);
DISPLAY 0.936170 (650 5100);
PAINT GREEN (650 5100);
DISPLAY INVISIBLE (650 5100);
FORCEADD TAP..6
R 2
(-1550 1825);
FORCEPROP 3 LASTPIN (-1600 1825) SIG_NAME M_F_DQ<11>
J 0
(-1590 1835);
DISPLAY 0.659574 (-1590 1835);
PAINT MONO (-1590 1835);
DISPLAY INVISIBLE (-1590 1835);
FORCEPROP 1 LASTPIN (-1600 1825) BN 11
J 2
(-1550 1835);
DISPLAY 0.617021 (-1550 1835);
PAINT PINK (-1550 1835);
FORCEPROP 2 LAST CDS_LIB mstr_standard
J 2
(-1550 1825);
DISPLAY 0.787234 (-1550 1825);
PAINT MONO (-1550 1825);
DISPLAY INVISIBLE (-1550 1825);
FORCEPROP 1 LAST BODY_TYPE PLUMBING
J 2
(-1550 1775);
DISPLAY 1.234043 (-1550 1775);
PAINT GREEN (-1550 1775);
DISPLAY INVISIBLE (-1550 1775);
FORCEPROP 1 LAST HDL_TAP TRUE
J 2
(-1875 1700);
DISPLAY 1.234043 (-1875 1700);
PAINT GREEN (-1875 1700);
DISPLAY INVISIBLE (-1875 1700);
FORCEPROP 1 LAST PATH I100
J 2
(-1550 1825);
DISPLAY 0.936170 (-1550 1825);
PAINT GREEN (-1550 1825);
DISPLAY INVISIBLE (-1550 1825);
FORCEADD TAP..6
R 2
(-1550 1775);
FORCEPROP 3 LASTPIN (-1600 1775) SIG_NAME M_F_DQ<8>
J 0
(-1590 1785);
DISPLAY 0.659574 (-1590 1785);
PAINT MONO (-1590 1785);
DISPLAY INVISIBLE (-1590 1785);
FORCEPROP 1 LASTPIN (-1600 1775) BN 8
J 2
(-1550 1785);
DISPLAY 0.617021 (-1550 1785);
PAINT PINK (-1550 1785);
FORCEPROP 2 LAST CDS_LIB mstr_standard
J 2
(-1550 1775);
DISPLAY 0.787234 (-1550 1775);
PAINT MONO (-1550 1775);
DISPLAY INVISIBLE (-1550 1775);
FORCEPROP 1 LAST BODY_TYPE PLUMBING
J 2
(-1550 1725);
DISPLAY 1.234043 (-1550 1725);
PAINT GREEN (-1550 1725);
DISPLAY INVISIBLE (-1550 1725);
FORCEPROP 1 LAST HDL_TAP TRUE
J 2
(-1875 1650);
DISPLAY 1.234043 (-1875 1650);
PAINT GREEN (-1875 1650);
DISPLAY INVISIBLE (-1875 1650);
FORCEPROP 1 LAST PATH I101
J 2
(-1550 1775);
DISPLAY 0.936170 (-1550 1775);
PAINT GREEN (-1550 1775);
DISPLAY INVISIBLE (-1550 1775);
FORCEADD TAP..6
R 2
(-1550 1675);
FORCEPROP 3 LASTPIN (-1600 1675) SIG_NAME M_F_DQ<6>
J 0
(-1590 1685);
DISPLAY 0.659574 (-1590 1685);
PAINT MONO (-1590 1685);
DISPLAY INVISIBLE (-1590 1685);
FORCEPROP 1 LASTPIN (-1600 1675) BN 6
J 2
(-1550 1685);
DISPLAY 0.617021 (-1550 1685);
PAINT PINK (-1550 1685);
FORCEPROP 2 LAST CDS_LIB mstr_standard
J 2
(-1550 1675);
DISPLAY 0.787234 (-1550 1675);
PAINT MONO (-1550 1675);
DISPLAY INVISIBLE (-1550 1675);
FORCEPROP 1 LAST BODY_TYPE PLUMBING
J 2
(-1550 1625);
DISPLAY 1.234043 (-1550 1625);
PAINT GREEN (-1550 1625);
DISPLAY INVISIBLE (-1550 1625);
FORCEPROP 1 LAST HDL_TAP TRUE
J 2
(-1875 1550);
DISPLAY 1.234043 (-1875 1550);
PAINT GREEN (-1875 1550);
DISPLAY INVISIBLE (-1875 1550);
FORCEPROP 1 LAST PATH I102
J 2
(-1550 1675);
DISPLAY 0.936170 (-1550 1675);
PAINT GREEN (-1550 1675);
DISPLAY INVISIBLE (-1550 1675);
FORCEADD TAP..6
R 2
(-1550 1725);
FORCEPROP 3 LASTPIN (-1600 1725) SIG_NAME M_F_DQ<9>
J 0
(-1590 1735);
DISPLAY 0.659574 (-1590 1735);
PAINT MONO (-1590 1735);
DISPLAY INVISIBLE (-1590 1735);
FORCEPROP 1 LASTPIN (-1600 1725) BN 9
J 2
(-1550 1735);
DISPLAY 0.617021 (-1550 1735);
PAINT PINK (-1550 1735);
FORCEPROP 2 LAST CDS_LIB mstr_standard
J 2
(-1550 1725);
DISPLAY 0.787234 (-1550 1725);
PAINT MONO (-1550 1725);
DISPLAY INVISIBLE (-1550 1725);
FORCEPROP 1 LAST BODY_TYPE PLUMBING
J 2
(-1550 1675);
DISPLAY 1.234043 (-1550 1675);
PAINT GREEN (-1550 1675);
DISPLAY INVISIBLE (-1550 1675);
FORCEPROP 1 LAST HDL_TAP TRUE
J 2
(-1875 1600);
DISPLAY 1.234043 (-1875 1600);
PAINT GREEN (-1875 1600);
DISPLAY INVISIBLE (-1875 1600);
FORCEPROP 1 LAST PATH I103
J 2
(-1550 1725);
DISPLAY 0.936170 (-1550 1725);
PAINT GREEN (-1550 1725);
DISPLAY INVISIBLE (-1550 1725);
FORCEADD TAP..6
R 2
(-1550 1625);
FORCEPROP 3 LASTPIN (-1600 1625) SIG_NAME M_F_DQ<7>
J 0
(-1590 1635);
DISPLAY 0.659574 (-1590 1635);
PAINT MONO (-1590 1635);
DISPLAY INVISIBLE (-1590 1635);
FORCEPROP 1 LASTPIN (-1600 1625) BN 7
J 2
(-1550 1635);
DISPLAY 0.617021 (-1550 1635);
PAINT PINK (-1550 1635);
FORCEPROP 2 LAST CDS_LIB mstr_standard
J 2
(-1550 1625);
DISPLAY 0.787234 (-1550 1625);
PAINT MONO (-1550 1625);
DISPLAY INVISIBLE (-1550 1625);
FORCEPROP 1 LAST BODY_TYPE PLUMBING
J 2
(-1550 1575);
DISPLAY 1.234043 (-1550 1575);
PAINT GREEN (-1550 1575);
DISPLAY INVISIBLE (-1550 1575);
FORCEPROP 1 LAST HDL_TAP TRUE
J 2
(-1875 1500);
DISPLAY 1.234043 (-1875 1500);
PAINT GREEN (-1875 1500);
DISPLAY INVISIBLE (-1875 1500);
FORCEPROP 1 LAST PATH I104
J 2
(-1550 1625);
DISPLAY 0.936170 (-1550 1625);
PAINT GREEN (-1550 1625);
DISPLAY INVISIBLE (-1550 1625);
FORCEADD TAP..6
R 2
(-1550 1575);
FORCEPROP 3 LASTPIN (-1600 1575) SIG_NAME M_F_DQ<4>
J 0
(-1590 1585);
DISPLAY 0.659574 (-1590 1585);
PAINT MONO (-1590 1585);
DISPLAY INVISIBLE (-1590 1585);
FORCEPROP 1 LASTPIN (-1600 1575) BN 4
J 2
(-1550 1585);
DISPLAY 0.617021 (-1550 1585);
PAINT PINK (-1550 1585);
FORCEPROP 2 LAST CDS_LIB mstr_standard
J 2
(-1550 1575);
DISPLAY 0.787234 (-1550 1575);
PAINT MONO (-1550 1575);
DISPLAY INVISIBLE (-1550 1575);
FORCEPROP 1 LAST BODY_TYPE PLUMBING
J 2
(-1550 1525);
DISPLAY 1.234043 (-1550 1525);
PAINT GREEN (-1550 1525);
DISPLAY INVISIBLE (-1550 1525);
FORCEPROP 1 LAST HDL_TAP TRUE
J 2
(-1875 1450);
DISPLAY 1.234043 (-1875 1450);
PAINT GREEN (-1875 1450);
DISPLAY INVISIBLE (-1875 1450);
FORCEPROP 1 LAST PATH I105
J 2
(-1550 1575);
DISPLAY 0.936170 (-1550 1575);
PAINT GREEN (-1550 1575);
DISPLAY INVISIBLE (-1550 1575);
FORCEADD TAP..6
R 2
(-1550 1475);
FORCEPROP 3 LASTPIN (-1600 1475) SIG_NAME M_F_DQ<2>
J 0
(-1590 1485);
DISPLAY 0.659574 (-1590 1485);
PAINT MONO (-1590 1485);
DISPLAY INVISIBLE (-1590 1485);
FORCEPROP 1 LASTPIN (-1600 1475) BN 2
J 2
(-1550 1485);
DISPLAY 0.617021 (-1550 1485);
PAINT PINK (-1550 1485);
FORCEPROP 2 LAST CDS_LIB mstr_standard
J 2
(-1550 1475);
DISPLAY 0.787234 (-1550 1475);
PAINT MONO (-1550 1475);
DISPLAY INVISIBLE (-1550 1475);
FORCEPROP 1 LAST BODY_TYPE PLUMBING
J 2
(-1550 1425);
DISPLAY 1.234043 (-1550 1425);
PAINT GREEN (-1550 1425);
DISPLAY INVISIBLE (-1550 1425);
FORCEPROP 1 LAST HDL_TAP TRUE
J 2
(-1875 1350);
DISPLAY 1.234043 (-1875 1350);
PAINT GREEN (-1875 1350);
DISPLAY INVISIBLE (-1875 1350);
FORCEPROP 1 LAST PATH I106
J 2
(-1550 1475);
DISPLAY 0.936170 (-1550 1475);
PAINT GREEN (-1550 1475);
DISPLAY INVISIBLE (-1550 1475);
FORCEADD TAP..6
R 2
(-1550 1525);
FORCEPROP 3 LASTPIN (-1600 1525) SIG_NAME M_F_DQ<5>
J 0
(-1590 1535);
DISPLAY 0.659574 (-1590 1535);
PAINT MONO (-1590 1535);
DISPLAY INVISIBLE (-1590 1535);
FORCEPROP 1 LASTPIN (-1600 1525) BN 5
J 2
(-1550 1535);
DISPLAY 0.617021 (-1550 1535);
PAINT PINK (-1550 1535);
FORCEPROP 2 LAST CDS_LIB mstr_standard
J 2
(-1550 1525);
DISPLAY 0.787234 (-1550 1525);
PAINT MONO (-1550 1525);
DISPLAY INVISIBLE (-1550 1525);
FORCEPROP 1 LAST BODY_TYPE PLUMBING
J 2
(-1550 1475);
DISPLAY 1.234043 (-1550 1475);
PAINT GREEN (-1550 1475);
DISPLAY INVISIBLE (-1550 1475);
FORCEPROP 1 LAST HDL_TAP TRUE
J 2
(-1875 1400);
DISPLAY 1.234043 (-1875 1400);
PAINT GREEN (-1875 1400);
DISPLAY INVISIBLE (-1875 1400);
FORCEPROP 1 LAST PATH I107
J 2
(-1550 1525);
DISPLAY 0.936170 (-1550 1525);
PAINT GREEN (-1550 1525);
DISPLAY INVISIBLE (-1550 1525);
FORCEADD TAP..6
R 2
(-1550 1375);
FORCEPROP 3 LASTPIN (-1600 1375) SIG_NAME M_F_DQ<0>
J 0
(-1590 1385);
DISPLAY 0.659574 (-1590 1385);
PAINT MONO (-1590 1385);
DISPLAY INVISIBLE (-1590 1385);
FORCEPROP 1 LASTPIN (-1600 1375) BN 0
J 2
(-1550 1385);
DISPLAY 0.617021 (-1550 1385);
PAINT PINK (-1550 1385);
FORCEPROP 2 LAST CDS_LIB mstr_standard
J 2
(-1550 1375);
DISPLAY 0.787234 (-1550 1375);
PAINT MONO (-1550 1375);
DISPLAY INVISIBLE (-1550 1375);
FORCEPROP 1 LAST BODY_TYPE PLUMBING
J 2
(-1550 1325);
DISPLAY 1.234043 (-1550 1325);
PAINT GREEN (-1550 1325);
DISPLAY INVISIBLE (-1550 1325);
FORCEPROP 1 LAST HDL_TAP TRUE
J 2
(-1875 1250);
DISPLAY 1.234043 (-1875 1250);
PAINT GREEN (-1875 1250);
DISPLAY INVISIBLE (-1875 1250);
FORCEPROP 1 LAST PATH I108
J 2
(-1550 1375);
DISPLAY 0.936170 (-1550 1375);
PAINT GREEN (-1550 1375);
DISPLAY INVISIBLE (-1550 1375);
FORCEADD TAP..6
R 2
(-1550 1425);
FORCEPROP 3 LASTPIN (-1600 1425) SIG_NAME M_F_DQ<3>
J 0
(-1590 1435);
DISPLAY 0.659574 (-1590 1435);
PAINT MONO (-1590 1435);
DISPLAY INVISIBLE (-1590 1435);
FORCEPROP 1 LASTPIN (-1600 1425) BN 3
J 2
(-1550 1435);
DISPLAY 0.617021 (-1550 1435);
PAINT PINK (-1550 1435);
FORCEPROP 2 LAST CDS_LIB mstr_standard
J 2
(-1550 1425);
DISPLAY 0.787234 (-1550 1425);
PAINT MONO (-1550 1425);
DISPLAY INVISIBLE (-1550 1425);
FORCEPROP 1 LAST BODY_TYPE PLUMBING
J 2
(-1550 1375);
DISPLAY 1.234043 (-1550 1375);
PAINT GREEN (-1550 1375);
DISPLAY INVISIBLE (-1550 1375);
FORCEPROP 1 LAST HDL_TAP TRUE
J 2
(-1875 1300);
DISPLAY 1.234043 (-1875 1300);
PAINT GREEN (-1875 1300);
DISPLAY INVISIBLE (-1875 1300);
FORCEPROP 1 LAST PATH I109
J 2
(-1550 1425);
DISPLAY 0.936170 (-1550 1425);
PAINT GREEN (-1550 1425);
DISPLAY INVISIBLE (-1550 1425);
FORCEADD TAP..6
R 2
(650 5000);
FORCEPROP 3 LASTPIN (600 5000) SIG_NAME M_F_DQS_DP<15>
J 0
(610 5010);
DISPLAY 0.659574 (610 5010);
PAINT MONO (610 5010);
DISPLAY INVISIBLE (610 5010);
FORCEPROP 1 LASTPIN (600 5000) BN 15
J 2
(650 5010);
DISPLAY 0.617021 (650 5010);
PAINT PINK (650 5010);
FORCEPROP 2 LAST CDS_LIB mstr_standard
J 0
(650 5000);
DISPLAY 0.787234 (650 5000);
PAINT MONO (650 5000);
DISPLAY INVISIBLE (650 5000);
FORCEPROP 1 LAST BODY_TYPE PLUMBING
J 2
(650 4950);
DISPLAY 1.234043 (650 4950);
PAINT GREEN (650 4950);
DISPLAY INVISIBLE (650 4950);
FORCEPROP 1 LAST HDL_TAP TRUE
J 2
(325 4875);
DISPLAY 1.234043 (325 4875);
PAINT GREEN (325 4875);
DISPLAY INVISIBLE (325 4875);
FORCEPROP 1 LAST PATH I11
J 2
(650 5000);
DISPLAY 0.936170 (650 5000);
PAINT GREEN (650 5000);
DISPLAY INVISIBLE (650 5000);
FORCEADD TAP..6
R 2
(-1550 1325);
FORCEPROP 3 LASTPIN (-1600 1325) SIG_NAME M_F_DQ<1>
J 0
(-1590 1335);
DISPLAY 0.659574 (-1590 1335);
PAINT MONO (-1590 1335);
DISPLAY INVISIBLE (-1590 1335);
FORCEPROP 1 LASTPIN (-1600 1325) BN 1
J 2
(-1550 1335);
DISPLAY 0.617021 (-1550 1335);
PAINT PINK (-1550 1335);
FORCEPROP 2 LAST CDS_LIB mstr_standard
J 2
(-1550 1325);
DISPLAY 0.787234 (-1550 1325);
PAINT MONO (-1550 1325);
DISPLAY INVISIBLE (-1550 1325);
FORCEPROP 1 LAST BODY_TYPE PLUMBING
J 2
(-1550 1275);
DISPLAY 1.234043 (-1550 1275);
PAINT GREEN (-1550 1275);
DISPLAY INVISIBLE (-1550 1275);
FORCEPROP 1 LAST HDL_TAP TRUE
J 2
(-1875 1200);
DISPLAY 1.234043 (-1875 1200);
PAINT GREEN (-1875 1200);
DISPLAY INVISIBLE (-1875 1200);
FORCEPROP 1 LAST PATH I110
J 2
(-1550 1325);
DISPLAY 0.936170 (-1550 1325);
PAINT GREEN (-1550 1325);
DISPLAY INVISIBLE (-1550 1325);
FORCEADD SCONN288_H44441004..1
(-2300 2825);
FORCEPROP 1 LAST LOCATION J4A1
J 0
(-2750 4725);
DISPLAY 0.617021 (-2750 4725);
PAINT AQUA (-2750 4725);
FORCEPROP 1 LAST PART_NUMBER H44441-004
J 0
(-2750 825);
DISPLAY 0.617021 (-2750 825);
PAINT BLUE (-2750 825);
FORCEPROP 1 LAST MATERIAL SCONN
J 0
(-2750 4675);
DISPLAY 0.617021 (-2750 4675);
PAINT SKYBLUE (-2750 4675);
FORCEPROP 2 LASTPIN (-2800 1325) $PN 146
J 2
(-2810 1335);
DISPLAY 0.617021 (-2810 1335);
PAINT ORANGE (-2810 1335);
FORCEPROP 2 LASTPIN (-2800 1675) $PN 284
J 2
(-2810 1685);
DISPLAY 0.617021 (-2810 1685);
PAINT ORANGE (-2810 1685);
FORCEPROP 2 LASTPIN (-2800 1475) $PN 285
J 2
(-2810 1485);
DISPLAY 0.617021 (-2810 1485);
PAINT ORANGE (-2810 1485);
FORCEPROP 2 LASTPIN (-2800 1425) $PN 141
J 2
(-2810 1435);
DISPLAY 0.617021 (-2810 1435);
PAINT ORANGE (-2810 1435);
FORCEPROP 2 LASTPIN (-2800 1025) $PN 230
J 2
(-2810 1035);
DISPLAY 0.617021 (-2810 1035);
PAINT ORANGE (-2810 1035);
FORCEPROP 2 LASTPIN (-2800 1625) $PN 238
J 2
(-2810 1635);
DISPLAY 0.617021 (-2810 1635);
PAINT ORANGE (-2810 1635);
FORCEPROP 2 LASTPIN (-2800 1575) $PN 140
J 2
(-2810 1585);
DISPLAY 0.617021 (-2810 1585);
PAINT ORANGE (-2810 1585);
FORCEPROP 2 LASTPIN (-2800 1525) $PN 139
J 2
(-2810 1535);
DISPLAY 0.617021 (-2810 1535);
PAINT ORANGE (-2810 1535);
FORCEPROP 2 LASTPIN (-2800 2975) $PN 237
J 2
(-2810 2985);
DISPLAY 0.617021 (-2810 2985);
PAINT ORANGE (-2810 2985);
FORCEPROP 2 LASTPIN (-2800 2925) $PN 93
J 2
(-2810 2935);
DISPLAY 0.617021 (-2810 2935);
PAINT ORANGE (-2810 2935);
FORCEPROP 2 LASTPIN (-2800 2875) $PN 89
J 2
(-2810 2885);
DISPLAY 0.617021 (-2810 2885);
PAINT ORANGE (-2810 2885);
FORCEPROP 2 LASTPIN (-2800 2825) $PN 84
J 2
(-2810 2835);
DISPLAY 0.617021 (-2810 2835);
PAINT ORANGE (-2810 2835);
FORCEPROP 2 LASTPIN (-2800 1225) $PN 144
J 2
(-2810 1235);
DISPLAY 0.617021 (-2810 1235);
PAINT ORANGE (-2810 1235);
FORCEPROP 2 LASTPIN (-2800 1175) $PN 227
J 2
(-2810 1185);
DISPLAY 0.617021 (-2810 1185);
PAINT ORANGE (-2810 1185);
FORCEPROP 2 LASTPIN (-2800 1125) $PN 205
J 2
(-2810 1135);
DISPLAY 0.617021 (-2810 1135);
PAINT ORANGE (-2810 1135);
FORCEPROP 2 LASTPIN (-2800 1925) $PN 58
J 2
(-2810 1935);
DISPLAY 0.617021 (-2810 1935);
PAINT ORANGE (-2810 1935);
FORCEPROP 2 LASTPIN (-2800 1975) $PN 222
J 2
(-2810 1985);
DISPLAY 0.617021 (-2810 1985);
PAINT ORANGE (-2810 1985);
FORCEPROP 2 LASTPIN (-2800 2575) $PN 91
J 2
(-2810 2585);
DISPLAY 0.617021 (-2810 2585);
PAINT ORANGE (-2810 2585);
FORCEPROP 2 LASTPIN (-2800 2525) $PN 87
J 2
(-2810 2535);
DISPLAY 0.617021 (-2810 2535);
PAINT ORANGE (-2810 2535);
FORCEPROP 2 LASTPIN (-2800 1875) $PN 78
J 2
(-2810 1885);
DISPLAY 0.617021 (-2810 1885);
PAINT ORANGE (-2810 1885);
FORCEPROP 2 LASTPIN (-1800 4475) $PN 280
J 0
(-1790 4485);
DISPLAY 0.617021 (-1790 4485);
PAINT ORANGE (-1790 4485);
FORCEPROP 2 LASTPIN (-1800 4425) $PN 135
J 0
(-1790 4435);
DISPLAY 0.617021 (-1790 4435);
PAINT ORANGE (-1790 4435);
FORCEPROP 2 LASTPIN (-1800 4375) $PN 273
J 0
(-1790 4385);
DISPLAY 0.617021 (-1790 4385);
PAINT ORANGE (-1790 4385);
FORCEPROP 2 LASTPIN (-1800 4325) $PN 128
J 0
(-1790 4335);
DISPLAY 0.617021 (-1790 4335);
PAINT ORANGE (-1790 4335);
FORCEPROP 2 LASTPIN (-1800 4275) $PN 282
J 0
(-1790 4285);
DISPLAY 0.617021 (-1790 4285);
PAINT ORANGE (-1790 4285);
FORCEPROP 2 LASTPIN (-1800 4225) $PN 137
J 0
(-1790 4235);
DISPLAY 0.617021 (-1790 4235);
PAINT ORANGE (-1790 4235);
FORCEPROP 2 LASTPIN (-1800 4175) $PN 275
J 0
(-1790 4185);
DISPLAY 0.617021 (-1790 4185);
PAINT ORANGE (-1790 4185);
FORCEPROP 2 LASTPIN (-1800 4125) $PN 130
J 0
(-1790 4135);
DISPLAY 0.617021 (-1790 4135);
PAINT ORANGE (-1790 4135);
FORCEPROP 2 LASTPIN (-1800 4075) $PN 269
J 0
(-1790 4085);
DISPLAY 0.617021 (-1790 4085);
PAINT ORANGE (-1790 4085);
FORCEPROP 2 LASTPIN (-1800 4025) $PN 124
J 0
(-1790 4035);
DISPLAY 0.617021 (-1790 4035);
PAINT ORANGE (-1790 4035);
FORCEPROP 2 LASTPIN (-1800 3975) $PN 262
J 0
(-1790 3985);
DISPLAY 0.617021 (-1790 3985);
PAINT ORANGE (-1790 3985);
FORCEPROP 2 LASTPIN (-1800 3925) $PN 117
J 0
(-1790 3935);
DISPLAY 0.617021 (-1790 3935);
PAINT ORANGE (-1790 3935);
FORCEPROP 2 LASTPIN (-1800 3875) $PN 271
J 0
(-1790 3885);
DISPLAY 0.617021 (-1790 3885);
PAINT ORANGE (-1790 3885);
FORCEPROP 2 LASTPIN (-1800 3825) $PN 126
J 0
(-1790 3835);
DISPLAY 0.617021 (-1790 3835);
PAINT ORANGE (-1790 3835);
FORCEPROP 2 LASTPIN (-1800 3775) $PN 264
J 0
(-1790 3785);
DISPLAY 0.617021 (-1790 3785);
PAINT ORANGE (-1790 3785);
FORCEPROP 2 LASTPIN (-1800 3725) $PN 119
J 0
(-1790 3735);
DISPLAY 0.617021 (-1790 3735);
PAINT ORANGE (-1790 3735);
FORCEPROP 2 LASTPIN (-1800 3675) $PN 258
J 0
(-1790 3685);
DISPLAY 0.617021 (-1790 3685);
PAINT ORANGE (-1790 3685);
FORCEPROP 2 LASTPIN (-1800 3625) $PN 113
J 0
(-1790 3635);
DISPLAY 0.617021 (-1790 3635);
PAINT ORANGE (-1790 3635);
FORCEPROP 2 LASTPIN (-1800 3575) $PN 251
J 0
(-1790 3585);
DISPLAY 0.617021 (-1790 3585);
PAINT ORANGE (-1790 3585);
FORCEPROP 2 LASTPIN (-1800 3525) $PN 106
J 0
(-1790 3535);
DISPLAY 0.617021 (-1790 3535);
PAINT ORANGE (-1790 3535);
FORCEPROP 2 LASTPIN (-1800 3475) $PN 260
J 0
(-1790 3485);
DISPLAY 0.617021 (-1790 3485);
PAINT ORANGE (-1790 3485);
FORCEPROP 2 LASTPIN (-1800 3425) $PN 115
J 0
(-1790 3435);
DISPLAY 0.617021 (-1790 3435);
PAINT ORANGE (-1790 3435);
FORCEPROP 2 LASTPIN (-1800 3375) $PN 253
J 0
(-1790 3385);
DISPLAY 0.617021 (-1790 3385);
PAINT ORANGE (-1790 3385);
FORCEPROP 2 LASTPIN (-1800 3325) $PN 108
J 0
(-1790 3335);
DISPLAY 0.617021 (-1790 3335);
PAINT ORANGE (-1790 3335);
FORCEPROP 2 LASTPIN (-1800 3275) $PN 247
J 0
(-1790 3285);
DISPLAY 0.617021 (-1790 3285);
PAINT ORANGE (-1790 3285);
FORCEPROP 2 LASTPIN (-1800 3225) $PN 102
J 0
(-1790 3235);
DISPLAY 0.617021 (-1790 3235);
PAINT ORANGE (-1790 3235);
FORCEPROP 2 LASTPIN (-1800 3175) $PN 240
J 0
(-1790 3185);
DISPLAY 0.617021 (-1790 3185);
PAINT ORANGE (-1790 3185);
FORCEPROP 2 LASTPIN (-1800 3125) $PN 95
J 0
(-1790 3135);
DISPLAY 0.617021 (-1790 3135);
PAINT ORANGE (-1790 3135);
FORCEPROP 2 LASTPIN (-1800 3075) $PN 249
J 0
(-1790 3085);
DISPLAY 0.617021 (-1790 3085);
PAINT ORANGE (-1790 3085);
FORCEPROP 2 LASTPIN (-1800 3025) $PN 104
J 0
(-1790 3035);
DISPLAY 0.617021 (-1790 3035);
PAINT ORANGE (-1790 3035);
FORCEPROP 2 LASTPIN (-1800 2975) $PN 242
J 0
(-1790 2985);
DISPLAY 0.617021 (-1790 2985);
PAINT ORANGE (-1790 2985);
FORCEPROP 2 LASTPIN (-1800 2925) $PN 97
J 0
(-1790 2935);
DISPLAY 0.617021 (-1790 2935);
PAINT ORANGE (-1790 2935);
FORCEPROP 2 LASTPIN (-1800 2875) $PN 188
J 0
(-1790 2885);
DISPLAY 0.617021 (-1790 2885);
PAINT ORANGE (-1790 2885);
FORCEPROP 2 LASTPIN (-1800 2825) $PN 43
J 0
(-1790 2835);
DISPLAY 0.617021 (-1790 2835);
PAINT ORANGE (-1790 2835);
FORCEPROP 2 LASTPIN (-1800 2775) $PN 181
J 0
(-1790 2785);
DISPLAY 0.617021 (-1790 2785);
PAINT ORANGE (-1790 2785);
FORCEPROP 2 LASTPIN (-1800 2725) $PN 36
J 0
(-1790 2735);
DISPLAY 0.617021 (-1790 2735);
PAINT ORANGE (-1790 2735);
FORCEPROP 2 LASTPIN (-1800 2675) $PN 190
J 0
(-1790 2685);
DISPLAY 0.617021 (-1790 2685);
PAINT ORANGE (-1790 2685);
FORCEPROP 2 LASTPIN (-1800 2625) $PN 45
J 0
(-1790 2635);
DISPLAY 0.617021 (-1790 2635);
PAINT ORANGE (-1790 2635);
FORCEPROP 2 LASTPIN (-1800 2575) $PN 183
J 0
(-1790 2585);
DISPLAY 0.617021 (-1790 2585);
PAINT ORANGE (-1790 2585);
FORCEPROP 2 LASTPIN (-1800 2525) $PN 38
J 0
(-1790 2535);
DISPLAY 0.617021 (-1790 2535);
PAINT ORANGE (-1790 2535);
FORCEPROP 2 LASTPIN (-1800 2475) $PN 177
J 0
(-1790 2485);
DISPLAY 0.617021 (-1790 2485);
PAINT ORANGE (-1790 2485);
FORCEPROP 2 LASTPIN (-1800 2425) $PN 32
J 0
(-1790 2435);
DISPLAY 0.617021 (-1790 2435);
PAINT ORANGE (-1790 2435);
FORCEPROP 2 LASTPIN (-1800 2375) $PN 170
J 0
(-1790 2385);
DISPLAY 0.617021 (-1790 2385);
PAINT ORANGE (-1790 2385);
FORCEPROP 2 LASTPIN (-1800 2325) $PN 25
J 0
(-1790 2335);
DISPLAY 0.617021 (-1790 2335);
PAINT ORANGE (-1790 2335);
FORCEPROP 2 LASTPIN (-1800 2275) $PN 179
J 0
(-1790 2285);
DISPLAY 0.617021 (-1790 2285);
PAINT ORANGE (-1790 2285);
FORCEPROP 2 LASTPIN (-1800 2225) $PN 34
J 0
(-1790 2235);
DISPLAY 0.617021 (-1790 2235);
PAINT ORANGE (-1790 2235);
FORCEPROP 2 LASTPIN (-1800 2175) $PN 172
J 0
(-1790 2185);
DISPLAY 0.617021 (-1790 2185);
PAINT ORANGE (-1790 2185);
FORCEPROP 2 LASTPIN (-1800 2125) $PN 27
J 0
(-1790 2135);
DISPLAY 0.617021 (-1790 2135);
PAINT ORANGE (-1790 2135);
FORCEPROP 2 LASTPIN (-1800 2075) $PN 166
J 0
(-1790 2085);
DISPLAY 0.617021 (-1790 2085);
PAINT ORANGE (-1790 2085);
FORCEPROP 2 LASTPIN (-1800 2025) $PN 21
J 0
(-1790 2035);
DISPLAY 0.617021 (-1790 2035);
PAINT ORANGE (-1790 2035);
FORCEPROP 2 LASTPIN (-1800 1975) $PN 159
J 0
(-1790 1985);
DISPLAY 0.617021 (-1790 1985);
PAINT ORANGE (-1790 1985);
FORCEPROP 2 LASTPIN (-1800 1925) $PN 14
J 0
(-1790 1935);
DISPLAY 0.617021 (-1790 1935);
PAINT ORANGE (-1790 1935);
FORCEPROP 2 LASTPIN (-1800 1875) $PN 168
J 0
(-1790 1885);
DISPLAY 0.617021 (-1790 1885);
PAINT ORANGE (-1790 1885);
FORCEPROP 2 LASTPIN (-1800 1825) $PN 23
J 0
(-1790 1835);
DISPLAY 0.617021 (-1790 1835);
PAINT ORANGE (-1790 1835);
FORCEPROP 2 LASTPIN (-1800 1775) $PN 161
J 0
(-1790 1785);
DISPLAY 0.617021 (-1790 1785);
PAINT ORANGE (-1790 1785);
FORCEPROP 2 LASTPIN (-1800 1725) $PN 16
J 0
(-1790 1735);
DISPLAY 0.617021 (-1790 1735);
PAINT ORANGE (-1790 1735);
FORCEPROP 2 LASTPIN (-1800 1675) $PN 155
J 0
(-1790 1685);
DISPLAY 0.617021 (-1790 1685);
PAINT ORANGE (-1790 1685);
FORCEPROP 2 LASTPIN (-1800 1625) $PN 10
J 0
(-1790 1635);
DISPLAY 0.617021 (-1790 1635);
PAINT ORANGE (-1790 1635);
FORCEPROP 2 LASTPIN (-1800 1575) $PN 148
J 0
(-1790 1585);
DISPLAY 0.617021 (-1790 1585);
PAINT ORANGE (-1790 1585);
FORCEPROP 2 LASTPIN (-1800 1525) $PN 3
J 0
(-1790 1535);
DISPLAY 0.617021 (-1790 1535);
PAINT ORANGE (-1790 1535);
FORCEPROP 2 LASTPIN (-1800 1475) $PN 157
J 0
(-1790 1485);
DISPLAY 0.617021 (-1790 1485);
PAINT ORANGE (-1790 1485);
FORCEPROP 2 LASTPIN (-1800 1425) $PN 12
J 0
(-1790 1435);
DISPLAY 0.617021 (-1790 1435);
PAINT ORANGE (-1790 1435);
FORCEPROP 2 LASTPIN (-1800 1375) $PN 150
J 0
(-1790 1385);
DISPLAY 0.617021 (-1790 1385);
PAINT ORANGE (-1790 1385);
FORCEPROP 2 LASTPIN (-1800 1325) $PN 5
J 0
(-1790 1335);
DISPLAY 0.617021 (-1790 1335);
PAINT ORANGE (-1790 1335);
FORCEPROP 2 LASTPIN (-2800 2725) $PN 203
J 2
(-2810 2735);
DISPLAY 0.617021 (-2810 2735);
PAINT ORANGE (-2810 2735);
FORCEPROP 2 LASTPIN (-2800 2675) $PN 60
J 2
(-2810 2685);
DISPLAY 0.617021 (-2810 2685);
PAINT ORANGE (-2810 2685);
FORCEPROP 2 LASTPIN (-2800 3275) $PN 218
J 2
(-2810 3285);
DISPLAY 0.617021 (-2810 3285);
PAINT ORANGE (-2810 3285);
FORCEPROP 2 LASTPIN (-2800 3225) $PN 219
J 2
(-2810 3235);
DISPLAY 0.617021 (-2810 3235);
PAINT ORANGE (-2810 3235);
FORCEPROP 2 LASTPIN (-2800 3175) $PN 74
J 2
(-2810 3185);
DISPLAY 0.617021 (-2810 3185);
PAINT ORANGE (-2810 3185);
FORCEPROP 2 LASTPIN (-2800 3125) $PN 75
J 2
(-2810 3135);
DISPLAY 0.617021 (-2810 3135);
PAINT ORANGE (-2810 3135);
FORCEPROP 2 LASTPIN (-2800 2425) $PN 199
J 2
(-2810 2435);
DISPLAY 0.617021 (-2810 2435);
PAINT ORANGE (-2810 2435);
FORCEPROP 2 LASTPIN (-2800 2375) $PN 54
J 2
(-2810 2385);
DISPLAY 0.617021 (-2810 2385);
PAINT ORANGE (-2810 2385);
FORCEPROP 2 LASTPIN (-2800 2325) $PN 192
J 2
(-2810 2335);
DISPLAY 0.617021 (-2810 2335);
PAINT ORANGE (-2810 2335);
FORCEPROP 2 LASTPIN (-2800 2275) $PN 47
J 2
(-2810 2285);
DISPLAY 0.617021 (-2810 2285);
PAINT ORANGE (-2810 2285);
FORCEPROP 2 LASTPIN (-2800 2225) $PN 201
J 2
(-2810 2235);
DISPLAY 0.617021 (-2810 2235);
PAINT ORANGE (-2810 2235);
FORCEPROP 2 LASTPIN (-2800 2175) $PN 56
J 2
(-2810 2185);
DISPLAY 0.617021 (-2810 2185);
PAINT ORANGE (-2810 2185);
FORCEPROP 2 LASTPIN (-2800 2125) $PN 194
J 2
(-2810 2135);
DISPLAY 0.617021 (-2810 2135);
PAINT ORANGE (-2810 2135);
FORCEPROP 2 LASTPIN (-2800 2075) $PN 49
J 2
(-2810 2085);
DISPLAY 0.617021 (-2810 2085);
PAINT ORANGE (-2810 2085);
FORCEPROP 2 LASTPIN (-2800 3025) $PN 235
J 2
(-2810 3035);
DISPLAY 0.617021 (-2810 3035);
PAINT ORANGE (-2810 3035);
FORCEPROP 2 LASTPIN (-2800 3425) $PN 207
J 2
(-2810 3435);
DISPLAY 0.617021 (-2810 3435);
PAINT ORANGE (-2810 3435);
FORCEPROP 2 LASTPIN (-2800 3375) $PN 63
J 2
(-2810 3385);
DISPLAY 0.617021 (-2810 3385);
PAINT ORANGE (-2810 3385);
FORCEPROP 2 LASTPIN (-2800 3525) $PN 224
J 2
(-2810 3535);
DISPLAY 0.617021 (-2810 3535);
PAINT ORANGE (-2810 3535);
FORCEPROP 2 LASTPIN (-2800 3475) $PN 81
J 2
(-2810 3485);
DISPLAY 0.617021 (-2810 3485);
PAINT ORANGE (-2810 3485);
FORCEPROP 2 LASTPIN (-2800 1825) $PN 208
J 2
(-2810 1835);
DISPLAY 0.617021 (-2810 1835);
PAINT ORANGE (-2810 1835);
FORCEPROP 2 LASTPIN (-2800 1775) $PN 62
J 2
(-2810 1785);
DISPLAY 0.617021 (-2810 1785);
PAINT ORANGE (-2810 1785);
FORCEPROP 2 LASTPIN (-2800 4475) $PN 234
J 2
(-2810 4485);
DISPLAY 0.617021 (-2810 4485);
PAINT ORANGE (-2810 4485);
FORCEPROP 2 LASTPIN (-2800 4425) $PN 82
J 2
(-2810 4435);
DISPLAY 0.617021 (-2810 4435);
PAINT ORANGE (-2810 4435);
FORCEPROP 2 LASTPIN (-2800 4375) $PN 86
J 2
(-2810 4385);
DISPLAY 0.617021 (-2810 4385);
PAINT ORANGE (-2810 4385);
FORCEPROP 2 LASTPIN (-2800 4325) $PN 228
J 2
(-2810 4335);
DISPLAY 0.617021 (-2810 4335);
PAINT ORANGE (-2810 4335);
FORCEPROP 2 LASTPIN (-2800 4275) $PN 232
J 2
(-2810 4285);
DISPLAY 0.617021 (-2810 4285);
PAINT ORANGE (-2810 4285);
FORCEPROP 2 LASTPIN (-2800 4225) $PN 65
J 2
(-2810 4235);
DISPLAY 0.617021 (-2810 4235);
PAINT ORANGE (-2810 4235);
FORCEPROP 2 LASTPIN (-2800 4175) $PN 210
J 2
(-2810 4185);
DISPLAY 0.617021 (-2810 4185);
PAINT ORANGE (-2810 4185);
FORCEPROP 2 LASTPIN (-2800 4125) $PN 225
J 2
(-2810 4135);
DISPLAY 0.617021 (-2810 4135);
PAINT ORANGE (-2810 4135);
FORCEPROP 2 LASTPIN (-2800 4075) $PN 66
J 2
(-2810 4085);
DISPLAY 0.617021 (-2810 4085);
PAINT ORANGE (-2810 4085);
FORCEPROP 2 LASTPIN (-2800 4025) $PN 68
J 2
(-2810 4035);
DISPLAY 0.617021 (-2810 4035);
PAINT ORANGE (-2810 4035);
FORCEPROP 2 LASTPIN (-2800 3975) $PN 211
J 2
(-2810 3985);
DISPLAY 0.617021 (-2810 3985);
PAINT ORANGE (-2810 3985);
FORCEPROP 2 LASTPIN (-2800 3925) $PN 69
J 2
(-2810 3935);
DISPLAY 0.617021 (-2810 3935);
PAINT ORANGE (-2810 3935);
FORCEPROP 2 LASTPIN (-2800 3875) $PN 213
J 2
(-2810 3885);
DISPLAY 0.617021 (-2810 3885);
PAINT ORANGE (-2810 3885);
FORCEPROP 2 LASTPIN (-2800 3825) $PN 214
J 2
(-2810 3835);
DISPLAY 0.617021 (-2810 3835);
PAINT ORANGE (-2810 3835);
FORCEPROP 2 LASTPIN (-2800 3775) $PN 71
J 2
(-2810 3785);
DISPLAY 0.617021 (-2810 3785);
PAINT ORANGE (-2810 3785);
FORCEPROP 2 LASTPIN (-2800 3725) $PN 216
J 2
(-2810 3735);
DISPLAY 0.617021 (-2810 3735);
PAINT ORANGE (-2810 3735);
FORCEPROP 2 LASTPIN (-2800 3675) $PN 72
J 2
(-2810 3685);
DISPLAY 0.617021 (-2810 3685);
PAINT ORANGE (-2810 3685);
FORCEPROP 2 LASTPIN (-2800 3625) $PN 79
J 2
(-2810 3635);
DISPLAY 0.617021 (-2810 3635);
PAINT ORANGE (-2810 3635);
FORCEPROP 1 LAST PACK_TYPE PIP
J 0
(-2750 4775);
PAINT SKYBLUE (-2750 4775);
DISPLAY INVISIBLE (-2750 4775);
FORCEPROP 2 LAST BOM_COST MEM
J 0
(-2300 2830);
PAINT ORANGE (-2300 2830);
DISPLAY INVISIBLE (-2300 2830);
FORCEPROP 2 LAST CDS_LIB mstr_sconn
J 0
(-2300 2825);
PAINT ORANGE (-2300 2825);
DISPLAY INVISIBLE (-2300 2825);
FORCEPROP 2 LAST SEC_TYPE PIP
J 0
(-2750 4800);
DISPLAY 1.021277 (-2750 4800);
PAINT ORANGE (-2750 4800);
DISPLAY INVISIBLE (-2750 4800);
FORCEPROP 2 LAST SEC 1
J 0
(-2750 4800);
DISPLAY 0.680851 (-2750 4800);
PAINT MONO (-2750 4800);
DISPLAY INVISIBLE (-2750 4800);
FORCEPROP 2 LAST CDS_LOCATION J4A1
J 0
(-2750 4725);
DISPLAY 0.617021 (-2750 4725);
PAINT AQUA (-2750 4725);
DISPLAY INVISIBLE (-2750 4725);
FORCEPROP 1 LAST PATH I111
J 0
(-2300 4675);
PAINT GREEN (-2300 4675);
DISPLAY INVISIBLE (-2300 4675);
FORCEPROP 2 LAST ROOM DDR4_CH_F
J 0
(-2300 2830);
PAINT ORANGE (-2300 2830);
DISPLAY INVISIBLE (-2300 2830);
FORCEADD TAP..6
(-3050 4475);
FORCEPROP 3 LASTPIN (-3000 4475) SIG_NAME M_F_MA<17>
J 0
(-2990 4485);
DISPLAY 0.659574 (-2990 4485);
PAINT MONO (-2990 4485);
DISPLAY INVISIBLE (-2990 4485);
FORCEPROP 1 LASTPIN (-3000 4475) BN 17
J 0
(-3050 4485);
DISPLAY 0.617021 (-3050 4485);
PAINT PINK (-3050 4485);
FORCEPROP 2 LAST CDS_LIB mstr_standard
J 0
(-3050 4475);
DISPLAY 0.787234 (-3050 4475);
PAINT MONO (-3050 4475);
DISPLAY INVISIBLE (-3050 4475);
FORCEPROP 1 LAST BODY_TYPE PLUMBING
J 0
(-3050 4425);
DISPLAY 1.234043 (-3050 4425);
PAINT GREEN (-3050 4425);
DISPLAY INVISIBLE (-3050 4425);
FORCEPROP 1 LAST HDL_TAP TRUE
J 0
(-2725 4350);
DISPLAY 1.234043 (-2725 4350);
PAINT GREEN (-2725 4350);
DISPLAY INVISIBLE (-2725 4350);
FORCEPROP 1 LAST PATH I112
J 0
(-3050 4475);
DISPLAY 0.936170 (-3050 4475);
PAINT GREEN (-3050 4475);
DISPLAY INVISIBLE (-3050 4475);
FORCEADD TAP..6
(-3050 4425);
FORCEPROP 3 LASTPIN (-3000 4425) SIG_NAME M_F_MA<16>
J 0
(-2990 4435);
DISPLAY 0.659574 (-2990 4435);
PAINT MONO (-2990 4435);
DISPLAY INVISIBLE (-2990 4435);
FORCEPROP 1 LASTPIN (-3000 4425) BN 16
J 0
(-3050 4435);
DISPLAY 0.617021 (-3050 4435);
PAINT PINK (-3050 4435);
FORCEPROP 2 LAST CDS_LIB mstr_standard
J 2
(-3050 4425);
DISPLAY 0.787234 (-3050 4425);
PAINT MONO (-3050 4425);
DISPLAY INVISIBLE (-3050 4425);
FORCEPROP 1 LAST BODY_TYPE PLUMBING
J 0
(-3050 4375);
DISPLAY 1.234043 (-3050 4375);
PAINT GREEN (-3050 4375);
DISPLAY INVISIBLE (-3050 4375);
FORCEPROP 1 LAST HDL_TAP TRUE
J 0
(-2725 4300);
DISPLAY 1.234043 (-2725 4300);
PAINT GREEN (-2725 4300);
DISPLAY INVISIBLE (-2725 4300);
FORCEPROP 1 LAST PATH I113
J 0
(-3050 4425);
DISPLAY 0.936170 (-3050 4425);
PAINT GREEN (-3050 4425);
DISPLAY INVISIBLE (-3050 4425);
FORCEADD TAP..6
(-3050 4375);
FORCEPROP 3 LASTPIN (-3000 4375) SIG_NAME M_F_MA<15>
J 0
(-2990 4385);
DISPLAY 0.659574 (-2990 4385);
PAINT MONO (-2990 4385);
DISPLAY INVISIBLE (-2990 4385);
FORCEPROP 1 LASTPIN (-3000 4375) BN 15
J 0
(-3050 4385);
DISPLAY 0.617021 (-3050 4385);
PAINT PINK (-3050 4385);
FORCEPROP 2 LAST CDS_LIB mstr_standard
J 2
(-3050 4375);
DISPLAY 0.787234 (-3050 4375);
PAINT MONO (-3050 4375);
DISPLAY INVISIBLE (-3050 4375);
FORCEPROP 1 LAST BODY_TYPE PLUMBING
J 0
(-3050 4325);
DISPLAY 1.234043 (-3050 4325);
PAINT GREEN (-3050 4325);
DISPLAY INVISIBLE (-3050 4325);
FORCEPROP 1 LAST HDL_TAP TRUE
J 0
(-2725 4250);
DISPLAY 1.234043 (-2725 4250);
PAINT GREEN (-2725 4250);
DISPLAY INVISIBLE (-2725 4250);
FORCEPROP 1 LAST PATH I114
J 0
(-3050 4375);
DISPLAY 0.936170 (-3050 4375);
PAINT GREEN (-3050 4375);
DISPLAY INVISIBLE (-3050 4375);
FORCEADD TAP..6
(-3050 4325);
FORCEPROP 3 LASTPIN (-3000 4325) SIG_NAME M_F_MA<14>
J 0
(-2990 4335);
DISPLAY 0.659574 (-2990 4335);
PAINT MONO (-2990 4335);
DISPLAY INVISIBLE (-2990 4335);
FORCEPROP 1 LASTPIN (-3000 4325) BN 14
J 0
(-3050 4335);
DISPLAY 0.617021 (-3050 4335);
PAINT PINK (-3050 4335);
FORCEPROP 2 LAST CDS_LIB mstr_standard
J 2
(-3050 4325);
DISPLAY 0.787234 (-3050 4325);
PAINT MONO (-3050 4325);
DISPLAY INVISIBLE (-3050 4325);
FORCEPROP 1 LAST BODY_TYPE PLUMBING
J 0
(-3050 4275);
DISPLAY 1.234043 (-3050 4275);
PAINT GREEN (-3050 4275);
DISPLAY INVISIBLE (-3050 4275);
FORCEPROP 1 LAST HDL_TAP TRUE
J 0
(-2725 4200);
DISPLAY 1.234043 (-2725 4200);
PAINT GREEN (-2725 4200);
DISPLAY INVISIBLE (-2725 4200);
FORCEPROP 1 LAST PATH I115
J 0
(-3050 4325);
DISPLAY 0.936170 (-3050 4325);
PAINT GREEN (-3050 4325);
DISPLAY INVISIBLE (-3050 4325);
FORCEADD TAP..6
(-3050 4275);
FORCEPROP 3 LASTPIN (-3000 4275) SIG_NAME M_F_MA<13>
J 0
(-2990 4285);
DISPLAY 0.659574 (-2990 4285);
PAINT MONO (-2990 4285);
DISPLAY INVISIBLE (-2990 4285);
FORCEPROP 1 LASTPIN (-3000 4275) BN 13
J 0
(-3050 4285);
DISPLAY 0.617021 (-3050 4285);
PAINT PINK (-3050 4285);
FORCEPROP 2 LAST CDS_LIB mstr_standard
J 2
(-3050 4275);
DISPLAY 0.787234 (-3050 4275);
PAINT MONO (-3050 4275);
DISPLAY INVISIBLE (-3050 4275);
FORCEPROP 1 LAST BODY_TYPE PLUMBING
J 0
(-3050 4225);
DISPLAY 1.234043 (-3050 4225);
PAINT GREEN (-3050 4225);
DISPLAY INVISIBLE (-3050 4225);
FORCEPROP 1 LAST HDL_TAP TRUE
J 0
(-2725 4150);
DISPLAY 1.234043 (-2725 4150);
PAINT GREEN (-2725 4150);
DISPLAY INVISIBLE (-2725 4150);
FORCEPROP 1 LAST PATH I116
J 0
(-3050 4275);
DISPLAY 0.936170 (-3050 4275);
PAINT GREEN (-3050 4275);
DISPLAY INVISIBLE (-3050 4275);
FORCEADD TAP..6
(-3050 4225);
FORCEPROP 3 LASTPIN (-3000 4225) SIG_NAME M_F_MA<12>
J 0
(-2990 4235);
DISPLAY 0.659574 (-2990 4235);
PAINT MONO (-2990 4235);
DISPLAY INVISIBLE (-2990 4235);
FORCEPROP 1 LASTPIN (-3000 4225) BN 12
J 0
(-3050 4235);
DISPLAY 0.617021 (-3050 4235);
PAINT PINK (-3050 4235);
FORCEPROP 2 LAST CDS_LIB mstr_standard
J 2
(-3050 4225);
DISPLAY 0.787234 (-3050 4225);
PAINT MONO (-3050 4225);
DISPLAY INVISIBLE (-3050 4225);
FORCEPROP 1 LAST BODY_TYPE PLUMBING
J 0
(-3050 4175);
DISPLAY 1.234043 (-3050 4175);
PAINT GREEN (-3050 4175);
DISPLAY INVISIBLE (-3050 4175);
FORCEPROP 1 LAST HDL_TAP TRUE
J 0
(-2725 4100);
DISPLAY 1.234043 (-2725 4100);
PAINT GREEN (-2725 4100);
DISPLAY INVISIBLE (-2725 4100);
FORCEPROP 1 LAST PATH I117
J 0
(-3050 4225);
DISPLAY 0.936170 (-3050 4225);
PAINT GREEN (-3050 4225);
DISPLAY INVISIBLE (-3050 4225);
FORCEADD TAP..6
(-3050 4175);
FORCEPROP 3 LASTPIN (-3000 4175) SIG_NAME M_F_MA<11>
J 0
(-2990 4185);
DISPLAY 0.659574 (-2990 4185);
PAINT MONO (-2990 4185);
DISPLAY INVISIBLE (-2990 4185);
FORCEPROP 1 LASTPIN (-3000 4175) BN 11
J 0
(-3050 4185);
DISPLAY 0.617021 (-3050 4185);
PAINT PINK (-3050 4185);
FORCEPROP 2 LAST CDS_LIB mstr_standard
J 2
(-3050 4175);
DISPLAY 0.787234 (-3050 4175);
PAINT MONO (-3050 4175);
DISPLAY INVISIBLE (-3050 4175);
FORCEPROP 1 LAST BODY_TYPE PLUMBING
J 0
(-3050 4125);
DISPLAY 1.234043 (-3050 4125);
PAINT GREEN (-3050 4125);
DISPLAY INVISIBLE (-3050 4125);
FORCEPROP 1 LAST HDL_TAP TRUE
J 0
(-2725 4050);
DISPLAY 1.234043 (-2725 4050);
PAINT GREEN (-2725 4050);
DISPLAY INVISIBLE (-2725 4050);
FORCEPROP 1 LAST PATH I118
J 0
(-3050 4175);
DISPLAY 0.936170 (-3050 4175);
PAINT GREEN (-3050 4175);
DISPLAY INVISIBLE (-3050 4175);
FORCEADD TAP..6
(-3050 4125);
FORCEPROP 3 LASTPIN (-3000 4125) SIG_NAME M_F_MA<10>
J 0
(-2990 4135);
DISPLAY 0.659574 (-2990 4135);
PAINT MONO (-2990 4135);
DISPLAY INVISIBLE (-2990 4135);
FORCEPROP 1 LASTPIN (-3000 4125) BN 10
J 0
(-3050 4135);
DISPLAY 0.617021 (-3050 4135);
PAINT PINK (-3050 4135);
FORCEPROP 2 LAST CDS_LIB mstr_standard
J 2
(-3050 4125);
DISPLAY 0.787234 (-3050 4125);
PAINT MONO (-3050 4125);
DISPLAY INVISIBLE (-3050 4125);
FORCEPROP 1 LAST BODY_TYPE PLUMBING
J 0
(-3050 4075);
DISPLAY 1.234043 (-3050 4075);
PAINT GREEN (-3050 4075);
DISPLAY INVISIBLE (-3050 4075);
FORCEPROP 1 LAST HDL_TAP TRUE
J 0
(-2725 4000);
DISPLAY 1.234043 (-2725 4000);
PAINT GREEN (-2725 4000);
DISPLAY INVISIBLE (-2725 4000);
FORCEPROP 1 LAST PATH I119
J 0
(-3050 4125);
DISPLAY 0.936170 (-3050 4125);
PAINT GREEN (-3050 4125);
DISPLAY INVISIBLE (-3050 4125);
FORCEADD TAP..6
R 2
(650 4900);
FORCEPROP 3 LASTPIN (600 4900) SIG_NAME M_F_DQS_DP<14>
J 0
(610 4910);
DISPLAY 0.659574 (610 4910);
PAINT MONO (610 4910);
DISPLAY INVISIBLE (610 4910);
FORCEPROP 1 LASTPIN (600 4900) BN 14
J 2
(650 4910);
DISPLAY 0.617021 (650 4910);
PAINT PINK (650 4910);
FORCEPROP 2 LAST CDS_LIB mstr_standard
J 0
(650 4900);
DISPLAY 0.787234 (650 4900);
PAINT MONO (650 4900);
DISPLAY INVISIBLE (650 4900);
FORCEPROP 1 LAST BODY_TYPE PLUMBING
J 2
(650 4850);
DISPLAY 1.234043 (650 4850);
PAINT GREEN (650 4850);
DISPLAY INVISIBLE (650 4850);
FORCEPROP 1 LAST HDL_TAP TRUE
J 2
(325 4775);
DISPLAY 1.234043 (325 4775);
PAINT GREEN (325 4775);
DISPLAY INVISIBLE (325 4775);
FORCEPROP 1 LAST PATH I12
J 2
(650 4900);
DISPLAY 0.936170 (650 4900);
PAINT GREEN (650 4900);
DISPLAY INVISIBLE (650 4900);
FORCEADD TAP..6
(-3050 4075);
FORCEPROP 3 LASTPIN (-3000 4075) SIG_NAME M_F_MA<9>
J 0
(-2990 4085);
DISPLAY 0.659574 (-2990 4085);
PAINT MONO (-2990 4085);
DISPLAY INVISIBLE (-2990 4085);
FORCEPROP 1 LASTPIN (-3000 4075) BN 9
J 0
(-3050 4085);
DISPLAY 0.617021 (-3050 4085);
PAINT PINK (-3050 4085);
FORCEPROP 2 LAST CDS_LIB mstr_standard
J 2
(-3050 4075);
DISPLAY 0.787234 (-3050 4075);
PAINT MONO (-3050 4075);
DISPLAY INVISIBLE (-3050 4075);
FORCEPROP 1 LAST BODY_TYPE PLUMBING
J 0
(-3050 4025);
DISPLAY 1.234043 (-3050 4025);
PAINT GREEN (-3050 4025);
DISPLAY INVISIBLE (-3050 4025);
FORCEPROP 1 LAST HDL_TAP TRUE
J 0
(-2725 3950);
DISPLAY 1.234043 (-2725 3950);
PAINT GREEN (-2725 3950);
DISPLAY INVISIBLE (-2725 3950);
FORCEPROP 1 LAST PATH I120
J 0
(-3050 4075);
DISPLAY 0.936170 (-3050 4075);
PAINT GREEN (-3050 4075);
DISPLAY INVISIBLE (-3050 4075);
FORCEADD TAP..6
(-3050 4025);
FORCEPROP 3 LASTPIN (-3000 4025) SIG_NAME M_F_MA<8>
J 0
(-2990 4035);
DISPLAY 0.659574 (-2990 4035);
PAINT MONO (-2990 4035);
DISPLAY INVISIBLE (-2990 4035);
FORCEPROP 1 LASTPIN (-3000 4025) BN 8
J 0
(-3050 4035);
DISPLAY 0.617021 (-3050 4035);
PAINT PINK (-3050 4035);
FORCEPROP 2 LAST CDS_LIB mstr_standard
J 2
(-3050 4025);
DISPLAY 0.787234 (-3050 4025);
PAINT MONO (-3050 4025);
DISPLAY INVISIBLE (-3050 4025);
FORCEPROP 1 LAST BODY_TYPE PLUMBING
J 0
(-3050 3975);
DISPLAY 1.234043 (-3050 3975);
PAINT GREEN (-3050 3975);
DISPLAY INVISIBLE (-3050 3975);
FORCEPROP 1 LAST HDL_TAP TRUE
J 0
(-2725 3900);
DISPLAY 1.234043 (-2725 3900);
PAINT GREEN (-2725 3900);
DISPLAY INVISIBLE (-2725 3900);
FORCEPROP 1 LAST PATH I121
J 0
(-3050 4025);
DISPLAY 0.936170 (-3050 4025);
PAINT GREEN (-3050 4025);
DISPLAY INVISIBLE (-3050 4025);
FORCEADD TAP..6
(-3050 3975);
FORCEPROP 3 LASTPIN (-3000 3975) SIG_NAME M_F_MA<7>
J 0
(-2990 3985);
DISPLAY 0.659574 (-2990 3985);
PAINT MONO (-2990 3985);
DISPLAY INVISIBLE (-2990 3985);
FORCEPROP 1 LASTPIN (-3000 3975) BN 7
J 0
(-3050 3985);
DISPLAY 0.617021 (-3050 3985);
PAINT PINK (-3050 3985);
FORCEPROP 2 LAST CDS_LIB mstr_standard
J 2
(-3050 3975);
DISPLAY 0.787234 (-3050 3975);
PAINT MONO (-3050 3975);
DISPLAY INVISIBLE (-3050 3975);
FORCEPROP 1 LAST BODY_TYPE PLUMBING
J 0
(-3050 3925);
DISPLAY 1.234043 (-3050 3925);
PAINT GREEN (-3050 3925);
DISPLAY INVISIBLE (-3050 3925);
FORCEPROP 1 LAST HDL_TAP TRUE
J 0
(-2725 3850);
DISPLAY 1.234043 (-2725 3850);
PAINT GREEN (-2725 3850);
DISPLAY INVISIBLE (-2725 3850);
FORCEPROP 1 LAST PATH I122
J 0
(-3050 3975);
DISPLAY 0.936170 (-3050 3975);
PAINT GREEN (-3050 3975);
DISPLAY INVISIBLE (-3050 3975);
FORCEADD TAP..6
(-3050 3925);
FORCEPROP 3 LASTPIN (-3000 3925) SIG_NAME M_F_MA<6>
J 0
(-2990 3935);
DISPLAY 0.659574 (-2990 3935);
PAINT MONO (-2990 3935);
DISPLAY INVISIBLE (-2990 3935);
FORCEPROP 1 LASTPIN (-3000 3925) BN 6
J 0
(-3050 3935);
DISPLAY 0.617021 (-3050 3935);
PAINT PINK (-3050 3935);
FORCEPROP 2 LAST CDS_LIB mstr_standard
J 2
(-3050 3925);
DISPLAY 0.787234 (-3050 3925);
PAINT MONO (-3050 3925);
DISPLAY INVISIBLE (-3050 3925);
FORCEPROP 1 LAST BODY_TYPE PLUMBING
J 0
(-3050 3875);
DISPLAY 1.234043 (-3050 3875);
PAINT GREEN (-3050 3875);
DISPLAY INVISIBLE (-3050 3875);
FORCEPROP 1 LAST HDL_TAP TRUE
J 0
(-2725 3800);
DISPLAY 1.234043 (-2725 3800);
PAINT GREEN (-2725 3800);
DISPLAY INVISIBLE (-2725 3800);
FORCEPROP 1 LAST PATH I123
J 0
(-3050 3925);
DISPLAY 0.936170 (-3050 3925);
PAINT GREEN (-3050 3925);
DISPLAY INVISIBLE (-3050 3925);
FORCEADD TAP..6
(-3050 3875);
FORCEPROP 3 LASTPIN (-3000 3875) SIG_NAME M_F_MA<5>
J 0
(-2990 3885);
DISPLAY 0.659574 (-2990 3885);
PAINT MONO (-2990 3885);
DISPLAY INVISIBLE (-2990 3885);
FORCEPROP 1 LASTPIN (-3000 3875) BN 5
J 0
(-3050 3885);
DISPLAY 0.617021 (-3050 3885);
PAINT PINK (-3050 3885);
FORCEPROP 2 LAST CDS_LIB mstr_standard
J 2
(-3050 3875);
DISPLAY 0.787234 (-3050 3875);
PAINT MONO (-3050 3875);
DISPLAY INVISIBLE (-3050 3875);
FORCEPROP 1 LAST BODY_TYPE PLUMBING
J 0
(-3050 3825);
DISPLAY 1.234043 (-3050 3825);
PAINT GREEN (-3050 3825);
DISPLAY INVISIBLE (-3050 3825);
FORCEPROP 1 LAST HDL_TAP TRUE
J 0
(-2725 3750);
DISPLAY 1.234043 (-2725 3750);
PAINT GREEN (-2725 3750);
DISPLAY INVISIBLE (-2725 3750);
FORCEPROP 1 LAST PATH I124
J 0
(-3050 3875);
DISPLAY 0.936170 (-3050 3875);
PAINT GREEN (-3050 3875);
DISPLAY INVISIBLE (-3050 3875);
FORCEADD TAP..6
(-3050 3825);
FORCEPROP 3 LASTPIN (-3000 3825) SIG_NAME M_F_MA<4>
J 0
(-2990 3835);
DISPLAY 0.659574 (-2990 3835);
PAINT MONO (-2990 3835);
DISPLAY INVISIBLE (-2990 3835);
FORCEPROP 1 LASTPIN (-3000 3825) BN 4
J 0
(-3050 3835);
DISPLAY 0.617021 (-3050 3835);
PAINT PINK (-3050 3835);
FORCEPROP 2 LAST CDS_LIB mstr_standard
J 2
(-3050 3825);
DISPLAY 0.787234 (-3050 3825);
PAINT MONO (-3050 3825);
DISPLAY INVISIBLE (-3050 3825);
FORCEPROP 1 LAST BODY_TYPE PLUMBING
J 0
(-3050 3775);
DISPLAY 1.234043 (-3050 3775);
PAINT GREEN (-3050 3775);
DISPLAY INVISIBLE (-3050 3775);
FORCEPROP 1 LAST HDL_TAP TRUE
J 0
(-2725 3700);
DISPLAY 1.234043 (-2725 3700);
PAINT GREEN (-2725 3700);
DISPLAY INVISIBLE (-2725 3700);
FORCEPROP 1 LAST PATH I125
J 0
(-3050 3825);
DISPLAY 0.936170 (-3050 3825);
PAINT GREEN (-3050 3825);
DISPLAY INVISIBLE (-3050 3825);
FORCEADD TAP..6
(-3050 3775);
FORCEPROP 3 LASTPIN (-3000 3775) SIG_NAME M_F_MA<3>
J 0
(-2990 3785);
DISPLAY 0.659574 (-2990 3785);
PAINT MONO (-2990 3785);
DISPLAY INVISIBLE (-2990 3785);
FORCEPROP 1 LASTPIN (-3000 3775) BN 3
J 0
(-3050 3785);
DISPLAY 0.617021 (-3050 3785);
PAINT PINK (-3050 3785);
FORCEPROP 2 LAST CDS_LIB mstr_standard
J 2
(-3050 3775);
DISPLAY 0.787234 (-3050 3775);
PAINT MONO (-3050 3775);
DISPLAY INVISIBLE (-3050 3775);
FORCEPROP 1 LAST BODY_TYPE PLUMBING
J 0
(-3050 3725);
DISPLAY 1.234043 (-3050 3725);
PAINT GREEN (-3050 3725);
DISPLAY INVISIBLE (-3050 3725);
FORCEPROP 1 LAST HDL_TAP TRUE
J 0
(-2725 3650);
DISPLAY 1.234043 (-2725 3650);
PAINT GREEN (-2725 3650);
DISPLAY INVISIBLE (-2725 3650);
FORCEPROP 1 LAST PATH I126
J 0
(-3050 3775);
DISPLAY 0.936170 (-3050 3775);
PAINT GREEN (-3050 3775);
DISPLAY INVISIBLE (-3050 3775);
FORCEADD TAP..6
(-3050 3725);
FORCEPROP 3 LASTPIN (-3000 3725) SIG_NAME M_F_MA<2>
J 0
(-2990 3735);
DISPLAY 0.659574 (-2990 3735);
PAINT MONO (-2990 3735);
DISPLAY INVISIBLE (-2990 3735);
FORCEPROP 1 LASTPIN (-3000 3725) BN 2
J 0
(-3050 3735);
DISPLAY 0.617021 (-3050 3735);
PAINT PINK (-3050 3735);
FORCEPROP 2 LAST CDS_LIB mstr_standard
J 2
(-3050 3725);
DISPLAY 0.787234 (-3050 3725);
PAINT MONO (-3050 3725);
DISPLAY INVISIBLE (-3050 3725);
FORCEPROP 1 LAST BODY_TYPE PLUMBING
J 0
(-3050 3675);
DISPLAY 1.234043 (-3050 3675);
PAINT GREEN (-3050 3675);
DISPLAY INVISIBLE (-3050 3675);
FORCEPROP 1 LAST HDL_TAP TRUE
J 0
(-2725 3600);
DISPLAY 1.234043 (-2725 3600);
PAINT GREEN (-2725 3600);
DISPLAY INVISIBLE (-2725 3600);
FORCEPROP 1 LAST PATH I127
J 0
(-3050 3725);
DISPLAY 0.936170 (-3050 3725);
PAINT GREEN (-3050 3725);
DISPLAY INVISIBLE (-3050 3725);
FORCEADD TAP..6
(-3050 3675);
FORCEPROP 3 LASTPIN (-3000 3675) SIG_NAME M_F_MA<1>
J 0
(-2990 3685);
DISPLAY 0.659574 (-2990 3685);
PAINT MONO (-2990 3685);
DISPLAY INVISIBLE (-2990 3685);
FORCEPROP 1 LASTPIN (-3000 3675) BN 1
J 0
(-3050 3685);
DISPLAY 0.617021 (-3050 3685);
PAINT PINK (-3050 3685);
FORCEPROP 2 LAST CDS_LIB mstr_standard
J 2
(-3050 3675);
DISPLAY 0.787234 (-3050 3675);
PAINT MONO (-3050 3675);
DISPLAY INVISIBLE (-3050 3675);
FORCEPROP 1 LAST BODY_TYPE PLUMBING
J 0
(-3050 3625);
DISPLAY 1.234043 (-3050 3625);
PAINT GREEN (-3050 3625);
DISPLAY INVISIBLE (-3050 3625);
FORCEPROP 1 LAST HDL_TAP TRUE
J 0
(-2725 3550);
DISPLAY 1.234043 (-2725 3550);
PAINT GREEN (-2725 3550);
DISPLAY INVISIBLE (-2725 3550);
FORCEPROP 1 LAST PATH I128
J 0
(-3050 3675);
DISPLAY 0.936170 (-3050 3675);
PAINT GREEN (-3050 3675);
DISPLAY INVISIBLE (-3050 3675);
FORCEADD TAP..6
(-3050 3625);
FORCEPROP 3 LASTPIN (-3000 3625) SIG_NAME M_F_MA<0>
J 0
(-2990 3635);
DISPLAY 0.659574 (-2990 3635);
PAINT MONO (-2990 3635);
DISPLAY INVISIBLE (-2990 3635);
FORCEPROP 1 LASTPIN (-3000 3625) BN 0
J 0
(-3050 3635);
DISPLAY 0.617021 (-3050 3635);
PAINT PINK (-3050 3635);
FORCEPROP 2 LAST CDS_LIB mstr_standard
J 2
(-3050 3625);
DISPLAY 0.787234 (-3050 3625);
PAINT MONO (-3050 3625);
DISPLAY INVISIBLE (-3050 3625);
FORCEPROP 1 LAST BODY_TYPE PLUMBING
J 0
(-3050 3575);
DISPLAY 1.234043 (-3050 3575);
PAINT GREEN (-3050 3575);
DISPLAY INVISIBLE (-3050 3575);
FORCEPROP 1 LAST HDL_TAP TRUE
J 0
(-2725 3500);
DISPLAY 1.234043 (-2725 3500);
PAINT GREEN (-2725 3500);
DISPLAY INVISIBLE (-2725 3500);
FORCEPROP 1 LAST PATH I129
J 0
(-3050 3625);
DISPLAY 0.936170 (-3050 3625);
PAINT GREEN (-3050 3625);
DISPLAY INVISIBLE (-3050 3625);
FORCEADD TAP..6
R 2
(650 4800);
FORCEPROP 3 LASTPIN (600 4800) SIG_NAME M_F_DQS_DP<13>
J 0
(610 4810);
DISPLAY 0.659574 (610 4810);
PAINT MONO (610 4810);
DISPLAY INVISIBLE (610 4810);
FORCEPROP 1 LASTPIN (600 4800) BN 13
J 2
(650 4810);
DISPLAY 0.617021 (650 4810);
PAINT PINK (650 4810);
FORCEPROP 2 LAST CDS_LIB mstr_standard
J 0
(650 4800);
DISPLAY 0.787234 (650 4800);
PAINT MONO (650 4800);
DISPLAY INVISIBLE (650 4800);
FORCEPROP 1 LAST BODY_TYPE PLUMBING
J 2
(650 4750);
DISPLAY 1.234043 (650 4750);
PAINT GREEN (650 4750);
DISPLAY INVISIBLE (650 4750);
FORCEPROP 1 LAST HDL_TAP TRUE
J 2
(325 4675);
DISPLAY 1.234043 (325 4675);
PAINT GREEN (325 4675);
DISPLAY INVISIBLE (325 4675);
FORCEPROP 1 LAST PATH I13
J 2
(650 4800);
DISPLAY 0.936170 (650 4800);
PAINT GREEN (650 4800);
DISPLAY INVISIBLE (650 4800);
FORCEADD TAP..6
(-3050 3525);
FORCEPROP 3 LASTPIN (-3000 3525) SIG_NAME M_F_BA<1>
J 0
(-2990 3535);
DISPLAY 0.659574 (-2990 3535);
PAINT MONO (-2990 3535);
DISPLAY INVISIBLE (-2990 3535);
FORCEPROP 1 LASTPIN (-3000 3525) BN 1
J 0
(-3050 3535);
DISPLAY 0.617021 (-3050 3535);
PAINT PINK (-3050 3535);
FORCEPROP 2 LAST CDS_LIB mstr_standard
J 0
(-3050 3525);
DISPLAY 0.787234 (-3050 3525);
PAINT MONO (-3050 3525);
DISPLAY INVISIBLE (-3050 3525);
FORCEPROP 1 LAST BODY_TYPE PLUMBING
J 0
(-3050 3475);
DISPLAY 1.234043 (-3050 3475);
PAINT GREEN (-3050 3475);
DISPLAY INVISIBLE (-3050 3475);
FORCEPROP 1 LAST HDL_TAP TRUE
J 0
(-2725 3400);
DISPLAY 1.234043 (-2725 3400);
PAINT GREEN (-2725 3400);
DISPLAY INVISIBLE (-2725 3400);
FORCEPROP 1 LAST PATH I130
J 0
(-3050 3525);
DISPLAY 0.936170 (-3050 3525);
PAINT GREEN (-3050 3525);
DISPLAY INVISIBLE (-3050 3525);
FORCEADD OFFPAGE..1
(-3700 4525);
FORCEPROP 2 LAST $XR0 28 
J 0
(-3921 4525);
DISPLAY 0.638298 (-3921 4525);
PAINT MONO (-3921 4525);
FORCEPROP 2 LAST $XR1 54 
J 0
(-4011 4525);
DISPLAY 0.638298 (-4011 4525);
PAINT MONO (-4011 4525);
FORCEPROP 2 LAST CDS_LIB mstr_standard
J 0
(-3700 4525);
DISPLAY 0.787234 (-3700 4525);
PAINT MONO (-3700 4525);
DISPLAY INVISIBLE (-3700 4525);
FORCEPROP 1 LAST OFFPAGE TRUE
J 0
(-3375 4400);
DISPLAY 0.936170 (-3375 4400);
PAINT GREEN (-3375 4400);
DISPLAY INVISIBLE (-3375 4400);
FORCEPROP 1 LAST COMMENT_BODY TRUE
J 0
(-3575 4425);
DISPLAY 0.936170 (-3575 4425);
PAINT GREEN (-3575 4425);
DISPLAY INVISIBLE (-3575 4425);
FORCEPROP 2 LAST PATH I131
J 0
(-3650 4600);
DISPLAY 0.787234 (-3650 4600);
PAINT MONO (-3650 4600);
DISPLAY INVISIBLE (-3650 4600);
FORCEADD OFFPAGE..1
(-3700 3575);
FORCEPROP 2 LAST $XR0 28 
J 0
(-3921 3575);
DISPLAY 0.638298 (-3921 3575);
PAINT MONO (-3921 3575);
FORCEPROP 2 LAST $XR1 54 
J 0
(-4011 3575);
DISPLAY 0.638298 (-4011 3575);
PAINT MONO (-4011 3575);
FORCEPROP 2 LAST CDS_LIB mstr_standard
J 0
(-3700 3575);
DISPLAY 0.787234 (-3700 3575);
PAINT MONO (-3700 3575);
DISPLAY INVISIBLE (-3700 3575);
FORCEPROP 1 LAST OFFPAGE TRUE
J 0
(-3375 3450);
DISPLAY 0.936170 (-3375 3450);
PAINT GREEN (-3375 3450);
DISPLAY INVISIBLE (-3375 3450);
FORCEPROP 1 LAST COMMENT_BODY TRUE
J 0
(-3575 3475);
DISPLAY 0.936170 (-3575 3475);
PAINT GREEN (-3575 3475);
DISPLAY INVISIBLE (-3575 3475);
FORCEPROP 2 LAST PATH I132
J 0
(-3650 3650);
DISPLAY 0.787234 (-3650 3650);
PAINT MONO (-3650 3650);
DISPLAY INVISIBLE (-3650 3650);
FORCEADD TAP..6
(-3050 3475);
FORCEPROP 3 LASTPIN (-3000 3475) SIG_NAME M_F_BA<0>
J 0
(-2990 3485);
DISPLAY 0.659574 (-2990 3485);
PAINT MONO (-2990 3485);
DISPLAY INVISIBLE (-2990 3485);
FORCEPROP 1 LASTPIN (-3000 3475) BN 0
J 0
(-3050 3485);
DISPLAY 0.617021 (-3050 3485);
PAINT PINK (-3050 3485);
FORCEPROP 2 LAST CDS_LIB mstr_standard
J 0
(-3050 3475);
DISPLAY 0.787234 (-3050 3475);
PAINT MONO (-3050 3475);
DISPLAY INVISIBLE (-3050 3475);
FORCEPROP 1 LAST BODY_TYPE PLUMBING
J 0
(-3050 3425);
DISPLAY 1.234043 (-3050 3425);
PAINT GREEN (-3050 3425);
DISPLAY INVISIBLE (-3050 3425);
FORCEPROP 1 LAST HDL_TAP TRUE
J 0
(-2725 3350);
DISPLAY 1.234043 (-2725 3350);
PAINT GREEN (-2725 3350);
DISPLAY INVISIBLE (-2725 3350);
FORCEPROP 1 LAST PATH I133
J 0
(-3050 3475);
DISPLAY 0.936170 (-3050 3475);
PAINT GREEN (-3050 3475);
DISPLAY INVISIBLE (-3050 3475);
FORCEADD TAP..6
(-3050 3425);
FORCEPROP 3 LASTPIN (-3000 3425) SIG_NAME M_F_BG<1>
J 0
(-2990 3435);
DISPLAY 0.659574 (-2990 3435);
PAINT MONO (-2990 3435);
DISPLAY INVISIBLE (-2990 3435);
FORCEPROP 1 LASTPIN (-3000 3425) BN 1
J 0
(-3050 3435);
DISPLAY 0.617021 (-3050 3435);
PAINT PINK (-3050 3435);
FORCEPROP 2 LAST CDS_LIB mstr_standard
J 0
(-3050 3425);
DISPLAY 0.787234 (-3050 3425);
PAINT MONO (-3050 3425);
DISPLAY INVISIBLE (-3050 3425);
FORCEPROP 1 LAST BODY_TYPE PLUMBING
J 0
(-3050 3375);
DISPLAY 1.234043 (-3050 3375);
PAINT GREEN (-3050 3375);
DISPLAY INVISIBLE (-3050 3375);
FORCEPROP 1 LAST HDL_TAP TRUE
J 0
(-2725 3300);
DISPLAY 1.234043 (-2725 3300);
PAINT GREEN (-2725 3300);
DISPLAY INVISIBLE (-2725 3300);
FORCEPROP 1 LAST PATH I134
J 0
(-3050 3425);
DISPLAY 0.936170 (-3050 3425);
PAINT GREEN (-3050 3425);
DISPLAY INVISIBLE (-3050 3425);
FORCEADD TAP..6
(-3050 3375);
FORCEPROP 3 LASTPIN (-3000 3375) SIG_NAME M_F_BG<0>
J 0
(-2990 3385);
DISPLAY 0.659574 (-2990 3385);
PAINT MONO (-2990 3385);
DISPLAY INVISIBLE (-2990 3385);
FORCEPROP 1 LASTPIN (-3000 3375) BN 0
J 0
(-3050 3385);
DISPLAY 0.617021 (-3050 3385);
PAINT PINK (-3050 3385);
FORCEPROP 2 LAST CDS_LIB mstr_standard
J 0
(-3050 3375);
DISPLAY 0.787234 (-3050 3375);
PAINT MONO (-3050 3375);
DISPLAY INVISIBLE (-3050 3375);
FORCEPROP 1 LAST BODY_TYPE PLUMBING
J 0
(-3050 3325);
DISPLAY 1.234043 (-3050 3325);
PAINT GREEN (-3050 3325);
DISPLAY INVISIBLE (-3050 3325);
FORCEPROP 1 LAST HDL_TAP TRUE
J 0
(-2725 3250);
DISPLAY 1.234043 (-2725 3250);
PAINT GREEN (-2725 3250);
DISPLAY INVISIBLE (-2725 3250);
FORCEPROP 1 LAST PATH I135
J 0
(-3050 3375);
DISPLAY 0.936170 (-3050 3375);
PAINT GREEN (-3050 3375);
DISPLAY INVISIBLE (-3050 3375);
FORCEADD OFFPAGE..1
(-3700 3075);
FORCEPROP 2 LAST $XR0 28 
J 0
(-3921 3075);
DISPLAY 0.638298 (-3921 3075);
PAINT MONO (-3921 3075);
FORCEPROP 2 LAST $XR1 54 
J 0
(-4011 3075);
DISPLAY 0.638298 (-4011 3075);
PAINT MONO (-4011 3075);
FORCEPROP 2 LAST CDS_LIB mstr_standard
J 0
(-3700 3075);
DISPLAY 0.787234 (-3700 3075);
PAINT MONO (-3700 3075);
DISPLAY INVISIBLE (-3700 3075);
FORCEPROP 1 LAST OFFPAGE TRUE
J 0
(-3375 2950);
DISPLAY 0.936170 (-3375 2950);
PAINT GREEN (-3375 2950);
DISPLAY INVISIBLE (-3375 2950);
FORCEPROP 1 LAST COMMENT_BODY TRUE
J 0
(-3575 2975);
DISPLAY 0.936170 (-3575 2975);
PAINT GREEN (-3575 2975);
DISPLAY INVISIBLE (-3575 2975);
FORCEPROP 2 LAST PATH I136
J 0
(-3650 3150);
DISPLAY 0.787234 (-3650 3150);
PAINT MONO (-3650 3150);
DISPLAY INVISIBLE (-3650 3150);
FORCEADD OFFPAGE..1
(-3700 3450);
FORCEPROP 2 LAST $XR0 28 
J 0
(-3921 3450);
DISPLAY 0.638298 (-3921 3450);
PAINT MONO (-3921 3450);
FORCEPROP 2 LAST $XR1 54 
J 0
(-4011 3450);
DISPLAY 0.638298 (-4011 3450);
PAINT MONO (-4011 3450);
FORCEPROP 2 LAST CDS_LIB mstr_standard
J 0
(-3700 3450);
DISPLAY 0.787234 (-3700 3450);
PAINT MONO (-3700 3450);
DISPLAY INVISIBLE (-3700 3450);
FORCEPROP 1 LAST OFFPAGE TRUE
J 0
(-3375 3325);
DISPLAY 0.936170 (-3375 3325);
PAINT GREEN (-3375 3325);
DISPLAY INVISIBLE (-3375 3325);
FORCEPROP 1 LAST COMMENT_BODY TRUE
J 0
(-3575 3350);
DISPLAY 0.936170 (-3575 3350);
PAINT GREEN (-3575 3350);
DISPLAY INVISIBLE (-3575 3350);
FORCEPROP 2 LAST PATH I137
J 0
(-3650 3525);
DISPLAY 0.787234 (-3650 3525);
PAINT MONO (-3650 3525);
DISPLAY INVISIBLE (-3650 3525);
FORCEADD TAP..6
(-3050 2375);
FORCEPROP 3 LASTPIN (-3000 2375) SIG_NAME M_F_ECC<7>
J 0
(-2990 2385);
DISPLAY 0.659574 (-2990 2385);
PAINT MONO (-2990 2385);
DISPLAY INVISIBLE (-2990 2385);
FORCEPROP 1 LASTPIN (-3000 2375) BN 7
J 0
(-3050 2385);
DISPLAY 0.617021 (-3050 2385);
PAINT PINK (-3050 2385);
FORCEPROP 2 LAST CDS_LIB mstr_standard
J 0
(-3050 2375);
DISPLAY 0.787234 (-3050 2375);
PAINT MONO (-3050 2375);
DISPLAY INVISIBLE (-3050 2375);
FORCEPROP 1 LAST BODY_TYPE PLUMBING
J 0
(-3050 2325);
DISPLAY 1.234043 (-3050 2325);
PAINT GREEN (-3050 2325);
DISPLAY INVISIBLE (-3050 2325);
FORCEPROP 1 LAST HDL_TAP TRUE
J 0
(-2725 2250);
DISPLAY 1.234043 (-2725 2250);
PAINT GREEN (-2725 2250);
DISPLAY INVISIBLE (-2725 2250);
FORCEPROP 1 LAST PATH I138
J 0
(-3050 2375);
DISPLAY 0.936170 (-3050 2375);
PAINT GREEN (-3050 2375);
DISPLAY INVISIBLE (-3050 2375);
FORCEADD TAP..6
(-3050 2425);
FORCEPROP 3 LASTPIN (-3000 2425) SIG_NAME M_F_ECC<6>
J 0
(-2990 2435);
DISPLAY 0.659574 (-2990 2435);
PAINT MONO (-2990 2435);
DISPLAY INVISIBLE (-2990 2435);
FORCEPROP 1 LASTPIN (-3000 2425) BN 6
J 0
(-3050 2435);
DISPLAY 0.617021 (-3050 2435);
PAINT PINK (-3050 2435);
FORCEPROP 2 LAST CDS_LIB mstr_standard
J 0
(-3050 2425);
DISPLAY 0.787234 (-3050 2425);
PAINT MONO (-3050 2425);
DISPLAY INVISIBLE (-3050 2425);
FORCEPROP 1 LAST BODY_TYPE PLUMBING
J 0
(-3050 2375);
DISPLAY 1.234043 (-3050 2375);
PAINT GREEN (-3050 2375);
DISPLAY INVISIBLE (-3050 2375);
FORCEPROP 1 LAST HDL_TAP TRUE
J 0
(-2725 2300);
DISPLAY 1.234043 (-2725 2300);
PAINT GREEN (-2725 2300);
DISPLAY INVISIBLE (-2725 2300);
FORCEPROP 1 LAST PATH I139
J 0
(-3050 2425);
DISPLAY 0.936170 (-3050 2425);
PAINT GREEN (-3050 2425);
DISPLAY INVISIBLE (-3050 2425);
FORCEADD TAP..6
R 2
(650 4600);
FORCEPROP 3 LASTPIN (600 4600) SIG_NAME M_F_DQS_DP<11>
J 0
(610 4610);
DISPLAY 0.659574 (610 4610);
PAINT MONO (610 4610);
DISPLAY INVISIBLE (610 4610);
FORCEPROP 1 LASTPIN (600 4600) BN 11
J 2
(650 4610);
DISPLAY 0.617021 (650 4610);
PAINT PINK (650 4610);
FORCEPROP 2 LAST CDS_LIB mstr_standard
J 0
(650 4600);
DISPLAY 0.787234 (650 4600);
PAINT MONO (650 4600);
DISPLAY INVISIBLE (650 4600);
FORCEPROP 1 LAST BODY_TYPE PLUMBING
J 2
(650 4550);
DISPLAY 1.234043 (650 4550);
PAINT GREEN (650 4550);
DISPLAY INVISIBLE (650 4550);
FORCEPROP 1 LAST HDL_TAP TRUE
J 2
(325 4475);
DISPLAY 1.234043 (325 4475);
PAINT GREEN (325 4475);
DISPLAY INVISIBLE (325 4475);
FORCEPROP 1 LAST PATH I14
J 2
(650 4600);
DISPLAY 0.936170 (650 4600);
PAINT GREEN (650 4600);
DISPLAY INVISIBLE (650 4600);
FORCEADD TAP..6
(-3050 2325);
FORCEPROP 3 LASTPIN (-3000 2325) SIG_NAME M_F_ECC<4>
J 0
(-2990 2335);
DISPLAY 0.659574 (-2990 2335);
PAINT MONO (-2990 2335);
DISPLAY INVISIBLE (-2990 2335);
FORCEPROP 1 LASTPIN (-3000 2325) BN 4
J 0
(-3050 2335);
DISPLAY 0.617021 (-3050 2335);
PAINT PINK (-3050 2335);
FORCEPROP 2 LAST CDS_LIB mstr_standard
J 0
(-3050 2325);
DISPLAY 0.787234 (-3050 2325);
PAINT MONO (-3050 2325);
DISPLAY INVISIBLE (-3050 2325);
FORCEPROP 1 LAST BODY_TYPE PLUMBING
J 0
(-3050 2275);
DISPLAY 1.234043 (-3050 2275);
PAINT GREEN (-3050 2275);
DISPLAY INVISIBLE (-3050 2275);
FORCEPROP 1 LAST HDL_TAP TRUE
J 0
(-2725 2200);
DISPLAY 1.234043 (-2725 2200);
PAINT GREEN (-2725 2200);
DISPLAY INVISIBLE (-2725 2200);
FORCEPROP 1 LAST PATH I140
J 0
(-3050 2325);
DISPLAY 0.936170 (-3050 2325);
PAINT GREEN (-3050 2325);
DISPLAY INVISIBLE (-3050 2325);
FORCEADD TAP..6
(-3050 2275);
FORCEPROP 3 LASTPIN (-3000 2275) SIG_NAME M_F_ECC<5>
J 0
(-2990 2285);
DISPLAY 0.659574 (-2990 2285);
PAINT MONO (-2990 2285);
DISPLAY INVISIBLE (-2990 2285);
FORCEPROP 1 LASTPIN (-3000 2275) BN 5
J 0
(-3050 2285);
DISPLAY 0.617021 (-3050 2285);
PAINT PINK (-3050 2285);
FORCEPROP 2 LAST CDS_LIB mstr_standard
J 0
(-3050 2275);
DISPLAY 0.787234 (-3050 2275);
PAINT MONO (-3050 2275);
DISPLAY INVISIBLE (-3050 2275);
FORCEPROP 1 LAST BODY_TYPE PLUMBING
J 0
(-3050 2225);
DISPLAY 1.234043 (-3050 2225);
PAINT GREEN (-3050 2225);
DISPLAY INVISIBLE (-3050 2225);
FORCEPROP 1 LAST HDL_TAP TRUE
J 0
(-2725 2150);
DISPLAY 1.234043 (-2725 2150);
PAINT GREEN (-2725 2150);
DISPLAY INVISIBLE (-2725 2150);
FORCEPROP 1 LAST PATH I141
J 0
(-3050 2275);
DISPLAY 0.936170 (-3050 2275);
PAINT GREEN (-3050 2275);
DISPLAY INVISIBLE (-3050 2275);
FORCEADD TAP..6
(-3050 2225);
FORCEPROP 3 LASTPIN (-3000 2225) SIG_NAME M_F_ECC<2>
J 0
(-2990 2235);
DISPLAY 0.659574 (-2990 2235);
PAINT MONO (-2990 2235);
DISPLAY INVISIBLE (-2990 2235);
FORCEPROP 1 LASTPIN (-3000 2225) BN 2
J 0
(-3050 2235);
DISPLAY 0.617021 (-3050 2235);
PAINT PINK (-3050 2235);
FORCEPROP 2 LAST CDS_LIB mstr_standard
J 0
(-3050 2225);
DISPLAY 0.787234 (-3050 2225);
PAINT MONO (-3050 2225);
DISPLAY INVISIBLE (-3050 2225);
FORCEPROP 1 LAST BODY_TYPE PLUMBING
J 0
(-3050 2175);
DISPLAY 1.234043 (-3050 2175);
PAINT GREEN (-3050 2175);
DISPLAY INVISIBLE (-3050 2175);
FORCEPROP 1 LAST HDL_TAP TRUE
J 0
(-2725 2100);
DISPLAY 1.234043 (-2725 2100);
PAINT GREEN (-2725 2100);
DISPLAY INVISIBLE (-2725 2100);
FORCEPROP 1 LAST PATH I142
J 0
(-3050 2225);
DISPLAY 0.936170 (-3050 2225);
PAINT GREEN (-3050 2225);
DISPLAY INVISIBLE (-3050 2225);
FORCEADD TAP..6
(-3050 2175);
FORCEPROP 3 LASTPIN (-3000 2175) SIG_NAME M_F_ECC<3>
J 0
(-2990 2185);
DISPLAY 0.659574 (-2990 2185);
PAINT MONO (-2990 2185);
DISPLAY INVISIBLE (-2990 2185);
FORCEPROP 1 LASTPIN (-3000 2175) BN 3
J 0
(-3050 2185);
DISPLAY 0.617021 (-3050 2185);
PAINT PINK (-3050 2185);
FORCEPROP 2 LAST CDS_LIB mstr_standard
J 0
(-3050 2175);
DISPLAY 0.787234 (-3050 2175);
PAINT MONO (-3050 2175);
DISPLAY INVISIBLE (-3050 2175);
FORCEPROP 1 LAST BODY_TYPE PLUMBING
J 0
(-3050 2125);
DISPLAY 1.234043 (-3050 2125);
PAINT GREEN (-3050 2125);
DISPLAY INVISIBLE (-3050 2125);
FORCEPROP 1 LAST HDL_TAP TRUE
J 0
(-2725 2050);
DISPLAY 1.234043 (-2725 2050);
PAINT GREEN (-2725 2050);
DISPLAY INVISIBLE (-2725 2050);
FORCEPROP 1 LAST PATH I143
J 0
(-3050 2175);
DISPLAY 0.936170 (-3050 2175);
PAINT GREEN (-3050 2175);
DISPLAY INVISIBLE (-3050 2175);
FORCEADD TAP..6
(-3050 2125);
FORCEPROP 3 LASTPIN (-3000 2125) SIG_NAME M_F_ECC<0>
J 0
(-2990 2135);
DISPLAY 0.659574 (-2990 2135);
PAINT MONO (-2990 2135);
DISPLAY INVISIBLE (-2990 2135);
FORCEPROP 1 LASTPIN (-3000 2125) BN 0
J 0
(-3050 2135);
DISPLAY 0.617021 (-3050 2135);
PAINT PINK (-3050 2135);
FORCEPROP 2 LAST CDS_LIB mstr_standard
J 0
(-3050 2125);
DISPLAY 0.787234 (-3050 2125);
PAINT MONO (-3050 2125);
DISPLAY INVISIBLE (-3050 2125);
FORCEPROP 1 LAST BODY_TYPE PLUMBING
J 0
(-3050 2075);
DISPLAY 1.234043 (-3050 2075);
PAINT GREEN (-3050 2075);
DISPLAY INVISIBLE (-3050 2075);
FORCEPROP 1 LAST HDL_TAP TRUE
J 0
(-2725 2000);
DISPLAY 1.234043 (-2725 2000);
PAINT GREEN (-2725 2000);
DISPLAY INVISIBLE (-2725 2000);
FORCEPROP 1 LAST PATH I144
J 0
(-3050 2125);
DISPLAY 0.936170 (-3050 2125);
PAINT GREEN (-3050 2125);
DISPLAY INVISIBLE (-3050 2125);
FORCEADD TAP..6
(-3050 2075);
FORCEPROP 3 LASTPIN (-3000 2075) SIG_NAME M_F_ECC<1>
J 0
(-2990 2085);
DISPLAY 0.659574 (-2990 2085);
PAINT MONO (-2990 2085);
DISPLAY INVISIBLE (-2990 2085);
FORCEPROP 1 LASTPIN (-3000 2075) BN 1
J 0
(-3050 2085);
DISPLAY 0.617021 (-3050 2085);
PAINT PINK (-3050 2085);
FORCEPROP 2 LAST CDS_LIB mstr_standard
J 0
(-3050 2075);
DISPLAY 0.787234 (-3050 2075);
PAINT MONO (-3050 2075);
DISPLAY INVISIBLE (-3050 2075);
FORCEPROP 1 LAST BODY_TYPE PLUMBING
J 0
(-3050 2025);
DISPLAY 1.234043 (-3050 2025);
PAINT GREEN (-3050 2025);
DISPLAY INVISIBLE (-3050 2025);
FORCEPROP 1 LAST HDL_TAP TRUE
J 0
(-2725 1950);
DISPLAY 1.234043 (-2725 1950);
PAINT GREEN (-2725 1950);
DISPLAY INVISIBLE (-2725 1950);
FORCEPROP 1 LAST PATH I145
J 0
(-3050 2075);
DISPLAY 0.936170 (-3050 2075);
PAINT GREEN (-3050 2075);
DISPLAY INVISIBLE (-3050 2075);
FORCEADD OFFPAGE..1
(-3900 1775);
FORCEPROP 2 LAST $XR0 28 
J 0
(-4181 1775);
DISPLAY 0.638298 (-4181 1775);
PAINT MONO (-4181 1775);
FORCEPROP 2 LAST $XR1 54 
J 0
(-4271 1775);
DISPLAY 0.638298 (-4271 1775);
PAINT MONO (-4271 1775);
FORCEPROP 2 LAST CDS_LIB mstr_standard
J 0
(-3900 1775);
DISPLAY 0.787234 (-3900 1775);
PAINT MONO (-3900 1775);
DISPLAY INVISIBLE (-3900 1775);
FORCEPROP 1 LAST OFFPAGE TRUE
J 0
(-3575 1650);
DISPLAY 0.936170 (-3575 1650);
PAINT GREEN (-3575 1650);
DISPLAY INVISIBLE (-3575 1650);
FORCEPROP 1 LAST COMMENT_BODY TRUE
J 0
(-3775 1675);
DISPLAY 0.936170 (-3775 1675);
PAINT GREEN (-3775 1675);
DISPLAY INVISIBLE (-3775 1675);
FORCEPROP 2 LAST PATH I146
J 0
(-3850 1850);
DISPLAY 0.787234 (-3850 1850);
PAINT MONO (-3850 1850);
DISPLAY INVISIBLE (-3850 1850);
FORCEADD OFFPAGE..1
(-3700 2425);
FORCEPROP 2 LAST $XR0 28 
J 0
(-3981 2425);
DISPLAY 0.638298 (-3981 2425);
PAINT MONO (-3981 2425);
FORCEPROP 2 LAST $XR1 54 
J 0
(-4071 2425);
DISPLAY 0.638298 (-4071 2425);
PAINT MONO (-4071 2425);
FORCEPROP 2 LAST CDS_LIB mstr_standard
J 0
(-3700 2425);
DISPLAY 0.787234 (-3700 2425);
PAINT MONO (-3700 2425);
DISPLAY INVISIBLE (-3700 2425);
FORCEPROP 1 LAST OFFPAGE TRUE
J 0
(-3375 2300);
DISPLAY 0.936170 (-3375 2300);
PAINT GREEN (-3375 2300);
DISPLAY INVISIBLE (-3375 2300);
FORCEPROP 1 LAST COMMENT_BODY TRUE
J 0
(-3575 2325);
DISPLAY 0.936170 (-3575 2325);
PAINT GREEN (-3575 2325);
DISPLAY INVISIBLE (-3575 2325);
FORCEPROP 2 LAST PATH I147
J 0
(-3650 2500);
DISPLAY 0.787234 (-3650 2500);
PAINT MONO (-3650 2500);
DISPLAY INVISIBLE (-3650 2500);
FORCEADD OFFPAGE..5
(-3925 1825);
FORCEPROP 2 LAST $XR0 54 
J 0
(-4179 1825);
DISPLAY 0.638298 (-4179 1825);
PAINT MONO (-4179 1825);
FORCEPROP 2 LAST $XR1 28 
J 0
(-4269 1825);
DISPLAY 0.638298 (-4269 1825);
PAINT MONO (-4269 1825);
FORCEPROP 2 LAST CDS_LIB mstr_standard
J 0
(-3925 1825);
DISPLAY 0.787234 (-3925 1825);
PAINT MONO (-3925 1825);
DISPLAY INVISIBLE (-3925 1825);
FORCEPROP 1 LAST OFFPAGE TRUE
J 0
(-3600 1700);
DISPLAY 1.404255 (-3600 1700);
PAINT GREEN (-3600 1700);
DISPLAY INVISIBLE (-3600 1700);
FORCEPROP 1 LAST COMMENT_BODY TRUE
J 0
(-3825 1750);
DISPLAY 1.404255 (-3825 1750);
PAINT GREEN (-3825 1750);
DISPLAY INVISIBLE (-3825 1750);
FORCEPROP 2 LAST PATH I148
J 0
(-3875 1900);
DISPLAY 0.787234 (-3875 1900);
PAINT MONO (-3875 1900);
DISPLAY INVISIBLE (-3875 1900);
FORCEADD OFFPAGE..1
(-3700 2375);
FORCEPROP 2 LAST $XR0 21 
J 0
(-3921 2375);
DISPLAY 0.638298 (-3921 2375);
PAINT MONO (-3921 2375);
FORCEPROP 2 LAST $XR1 49 
J 0
(-4011 2375);
DISPLAY 0.638298 (-4011 2375);
PAINT MONO (-4011 2375);
FORCEPROP 2 LAST $XR2 50 
J 0
(-4101 2375);
DISPLAY 0.638298 (-4101 2375);
PAINT MONO (-4101 2375);
FORCEPROP 2 LAST $XR3 51 
J 0
(-4191 2375);
DISPLAY 0.638298 (-4191 2375);
PAINT MONO (-4191 2375);
FORCEPROP 2 LAST $XR4 52 
J 0
(-4281 2375);
DISPLAY 0.638298 (-4281 2375);
PAINT MONO (-4281 2375);
FORCEPROP 2 LAST $XR5 54 
J 0
(-4371 2375);
DISPLAY 0.638298 (-4371 2375);
PAINT MONO (-4371 2375);
FORCEPROP 2 LAST CDS_LIB mstr_standard
J 0
(-3700 2375);
DISPLAY 0.787234 (-3700 2375);
PAINT MONO (-3700 2375);
DISPLAY INVISIBLE (-3700 2375);
FORCEPROP 1 LAST OFFPAGE TRUE
J 0
(-3375 2250);
DISPLAY 0.936170 (-3375 2250);
PAINT GREEN (-3375 2250);
DISPLAY INVISIBLE (-3375 2250);
FORCEPROP 1 LAST COMMENT_BODY TRUE
J 0
(-3575 2275);
DISPLAY 0.936170 (-3575 2275);
PAINT GREEN (-3575 2275);
DISPLAY INVISIBLE (-3575 2275);
FORCEPROP 2 LAST PATH I149
J 0
(-3650 2450);
DISPLAY 0.787234 (-3650 2450);
PAINT MONO (-3650 2450);
DISPLAY INVISIBLE (-3650 2450);
FORCEADD TAP..6
R 2
(650 4700);
FORCEPROP 3 LASTPIN (600 4700) SIG_NAME M_F_DQS_DP<12>
J 0
(610 4710);
DISPLAY 0.659574 (610 4710);
PAINT MONO (610 4710);
DISPLAY INVISIBLE (610 4710);
FORCEPROP 1 LASTPIN (600 4700) BN 12
J 2
(650 4710);
DISPLAY 0.617021 (650 4710);
PAINT PINK (650 4710);
FORCEPROP 2 LAST CDS_LIB mstr_standard
J 0
(650 4700);
DISPLAY 0.787234 (650 4700);
PAINT MONO (650 4700);
DISPLAY INVISIBLE (650 4700);
FORCEPROP 1 LAST BODY_TYPE PLUMBING
J 2
(650 4650);
DISPLAY 1.234043 (650 4650);
PAINT GREEN (650 4650);
DISPLAY INVISIBLE (650 4650);
FORCEPROP 1 LAST HDL_TAP TRUE
J 2
(325 4575);
DISPLAY 1.234043 (325 4575);
PAINT GREEN (325 4575);
DISPLAY INVISIBLE (325 4575);
FORCEPROP 1 LAST PATH I15
J 2
(650 4700);
DISPLAY 0.936170 (650 4700);
PAINT GREEN (650 4700);
DISPLAY INVISIBLE (650 4700);
FORCEADD OFFPAGE..6
(-3700 2475);
FORCEPROP 2 LAST $XR0 28 
J 0
(-3979 2475);
DISPLAY 0.638298 (-3979 2475);
PAINT MONO (-3979 2475);
FORCEPROP 2 LAST $XR1 54 
J 0
(-4069 2475);
DISPLAY 0.638298 (-4069 2475);
PAINT MONO (-4069 2475);
FORCEPROP 2 LAST CDS_LIB mstr_standard
J 0
(-3700 2475);
DISPLAY 0.787234 (-3700 2475);
PAINT MONO (-3700 2475);
DISPLAY INVISIBLE (-3700 2475);
FORCEPROP 1 LAST OFFPAGE TRUE
J 0
(-3375 2350);
DISPLAY 0.936170 (-3375 2350);
PAINT GREEN (-3375 2350);
DISPLAY INVISIBLE (-3375 2350);
FORCEPROP 1 LAST COMMENT_BODY TRUE
J 0
(-3600 2400);
DISPLAY 0.936170 (-3600 2400);
PAINT GREEN (-3600 2400);
DISPLAY INVISIBLE (-3600 2400);
FORCEPROP 2 LAST PATH I150
J 0
(-3650 2550);
DISPLAY 0.787234 (-3650 2550);
PAINT MONO (-3650 2550);
DISPLAY INVISIBLE (-3650 2550);
FORCEADD TAP..6
(-3050 3275);
FORCEPROP 3 LASTPIN (-3000 3275) SIG_NAME M_F_CLK_DP<1>
J 0
(-2990 3285);
DISPLAY 0.659574 (-2990 3285);
PAINT MONO (-2990 3285);
DISPLAY INVISIBLE (-2990 3285);
FORCEPROP 1 LASTPIN (-3000 3275) BN 1
J 0
(-3050 3285);
DISPLAY 0.617021 (-3050 3285);
PAINT PINK (-3050 3285);
FORCEPROP 2 LAST CDS_LIB mstr_standard
J 0
(-3050 3275);
DISPLAY 0.787234 (-3050 3275);
PAINT MONO (-3050 3275);
DISPLAY INVISIBLE (-3050 3275);
FORCEPROP 1 LAST BODY_TYPE PLUMBING
J 0
(-3050 3225);
DISPLAY 1.234043 (-3050 3225);
PAINT GREEN (-3050 3225);
DISPLAY INVISIBLE (-3050 3225);
FORCEPROP 1 LAST HDL_TAP TRUE
J 0
(-2725 3150);
DISPLAY 1.234043 (-2725 3150);
PAINT GREEN (-2725 3150);
DISPLAY INVISIBLE (-2725 3150);
FORCEPROP 1 LAST PATH I152
J 0
(-3050 3275);
DISPLAY 0.936170 (-3050 3275);
PAINT GREEN (-3050 3275);
DISPLAY INVISIBLE (-3050 3275);
FORCEADD TAP..6
(-3050 3175);
FORCEPROP 3 LASTPIN (-3000 3175) SIG_NAME M_F_CLK_DP<0>
J 0
(-2990 3185);
DISPLAY 0.659574 (-2990 3185);
PAINT MONO (-2990 3185);
DISPLAY INVISIBLE (-2990 3185);
FORCEPROP 1 LASTPIN (-3000 3175) BN 0
J 0
(-3050 3185);
DISPLAY 0.617021 (-3050 3185);
PAINT PINK (-3050 3185);
FORCEPROP 2 LAST CDS_LIB mstr_standard
J 0
(-3050 3175);
DISPLAY 0.787234 (-3050 3175);
PAINT MONO (-3050 3175);
DISPLAY INVISIBLE (-3050 3175);
FORCEPROP 1 LAST BODY_TYPE PLUMBING
J 0
(-3050 3125);
DISPLAY 1.234043 (-3050 3125);
PAINT GREEN (-3050 3125);
DISPLAY INVISIBLE (-3050 3125);
FORCEPROP 1 LAST HDL_TAP TRUE
J 0
(-2725 3050);
DISPLAY 1.234043 (-2725 3050);
PAINT GREEN (-2725 3050);
DISPLAY INVISIBLE (-2725 3050);
FORCEPROP 1 LAST PATH I153
J 0
(-3050 3175);
DISPLAY 0.936170 (-3050 3175);
PAINT GREEN (-3050 3175);
DISPLAY INVISIBLE (-3050 3175);
FORCEADD TAP..6
(-3250 3225);
FORCEPROP 3 LASTPIN (-3200 3225) SIG_NAME M_F_CLK_DN<1>
J 0
(-3190 3235);
DISPLAY 0.659574 (-3190 3235);
PAINT MONO (-3190 3235);
DISPLAY INVISIBLE (-3190 3235);
FORCEPROP 1 LASTPIN (-3200 3225) BN 1
J 0
(-3250 3235);
DISPLAY 0.617021 (-3250 3235);
PAINT PINK (-3250 3235);
FORCEPROP 2 LAST CDS_LIB mstr_standard
J 0
(-3250 3225);
DISPLAY 0.787234 (-3250 3225);
PAINT MONO (-3250 3225);
DISPLAY INVISIBLE (-3250 3225);
FORCEPROP 1 LAST BODY_TYPE PLUMBING
J 0
(-3250 3175);
DISPLAY 1.234043 (-3250 3175);
PAINT GREEN (-3250 3175);
DISPLAY INVISIBLE (-3250 3175);
FORCEPROP 1 LAST HDL_TAP TRUE
J 0
(-2925 3100);
DISPLAY 1.234043 (-2925 3100);
PAINT GREEN (-2925 3100);
DISPLAY INVISIBLE (-2925 3100);
FORCEPROP 1 LAST PATH I154
J 0
(-3250 3225);
DISPLAY 0.936170 (-3250 3225);
PAINT GREEN (-3250 3225);
DISPLAY INVISIBLE (-3250 3225);
FORCEADD TAP..6
(-3250 3125);
FORCEPROP 3 LASTPIN (-3200 3125) SIG_NAME M_F_CLK_DN<0>
J 0
(-3190 3135);
DISPLAY 0.659574 (-3190 3135);
PAINT MONO (-3190 3135);
DISPLAY INVISIBLE (-3190 3135);
FORCEPROP 1 LASTPIN (-3200 3125) BN 0
J 0
(-3250 3135);
DISPLAY 0.617021 (-3250 3135);
PAINT PINK (-3250 3135);
FORCEPROP 2 LAST CDS_LIB mstr_standard
J 0
(-3250 3125);
DISPLAY 0.787234 (-3250 3125);
PAINT MONO (-3250 3125);
DISPLAY INVISIBLE (-3250 3125);
FORCEPROP 1 LAST BODY_TYPE PLUMBING
J 0
(-3250 3075);
DISPLAY 1.234043 (-3250 3075);
PAINT GREEN (-3250 3075);
DISPLAY INVISIBLE (-3250 3075);
FORCEPROP 1 LAST HDL_TAP TRUE
J 0
(-2925 3000);
DISPLAY 1.234043 (-2925 3000);
PAINT GREEN (-2925 3000);
DISPLAY INVISIBLE (-2925 3000);
FORCEPROP 1 LAST PATH I155
J 0
(-3250 3125);
DISPLAY 0.936170 (-3250 3125);
PAINT GREEN (-3250 3125);
DISPLAY INVISIBLE (-3250 3125);
FORCEADD OFFPAGE..1
(-3700 3325);
FORCEPROP 2 LAST $XR0 28 
J 0
(-3921 3325);
DISPLAY 0.638298 (-3921 3325);
PAINT MONO (-3921 3325);
FORCEPROP 2 LAST $XR1 54 
J 0
(-4011 3325);
DISPLAY 0.638298 (-4011 3325);
PAINT MONO (-4011 3325);
FORCEPROP 2 LAST CDS_LIB mstr_standard
J 0
(-3700 3325);
DISPLAY 0.787234 (-3700 3325);
PAINT MONO (-3700 3325);
DISPLAY INVISIBLE (-3700 3325);
FORCEPROP 1 LAST OFFPAGE TRUE
J 0
(-3375 3200);
DISPLAY 0.936170 (-3375 3200);
PAINT GREEN (-3375 3200);
DISPLAY INVISIBLE (-3375 3200);
FORCEPROP 1 LAST COMMENT_BODY TRUE
J 0
(-3575 3225);
DISPLAY 0.936170 (-3575 3225);
PAINT GREEN (-3575 3225);
DISPLAY INVISIBLE (-3575 3225);
FORCEPROP 2 LAST PATH I156
J 0
(-3650 3400);
DISPLAY 0.787234 (-3650 3400);
PAINT MONO (-3650 3400);
DISPLAY INVISIBLE (-3650 3400);
FORCEADD OFFPAGE..1
(-3700 3275);
FORCEPROP 2 LAST $XR0 28 
J 0
(-3921 3275);
DISPLAY 0.638298 (-3921 3275);
PAINT MONO (-3921 3275);
FORCEPROP 2 LAST $XR1 54 
J 0
(-4011 3275);
DISPLAY 0.638298 (-4011 3275);
PAINT MONO (-4011 3275);
FORCEPROP 2 LAST CDS_LIB mstr_standard
J 0
(-3700 3275);
DISPLAY 0.787234 (-3700 3275);
PAINT MONO (-3700 3275);
DISPLAY INVISIBLE (-3700 3275);
FORCEPROP 1 LAST OFFPAGE TRUE
J 0
(-3375 3150);
DISPLAY 0.936170 (-3375 3150);
PAINT GREEN (-3375 3150);
DISPLAY INVISIBLE (-3375 3150);
FORCEPROP 1 LAST COMMENT_BODY TRUE
J 0
(-3575 3175);
DISPLAY 0.936170 (-3575 3175);
PAINT GREEN (-3575 3175);
DISPLAY INVISIBLE (-3575 3175);
FORCEPROP 2 LAST PATH I157
J 0
(-3650 3350);
DISPLAY 0.787234 (-3650 3350);
PAINT MONO (-3650 3350);
DISPLAY INVISIBLE (-3650 3350);
FORCEADD TAP..6
(-3050 2975);
FORCEPROP 3 LASTPIN (-3000 2975) SIG_NAME M_F_CS_N<3>
J 0
(-2990 2985);
DISPLAY 0.659574 (-2990 2985);
PAINT MONO (-2990 2985);
DISPLAY INVISIBLE (-2990 2985);
FORCEPROP 1 LASTPIN (-3000 2975) BN 3
J 0
(-3050 2985);
DISPLAY 0.617021 (-3050 2985);
PAINT PINK (-3050 2985);
FORCEPROP 2 LAST CDS_LIB mstr_standard
J 0
(-3050 2975);
DISPLAY 0.787234 (-3050 2975);
PAINT MONO (-3050 2975);
DISPLAY INVISIBLE (-3050 2975);
FORCEPROP 1 LAST BODY_TYPE PLUMBING
J 0
(-3050 2925);
DISPLAY 1.234043 (-3050 2925);
PAINT GREEN (-3050 2925);
DISPLAY INVISIBLE (-3050 2925);
FORCEPROP 1 LAST HDL_TAP TRUE
J 0
(-2725 2850);
DISPLAY 1.234043 (-2725 2850);
PAINT GREEN (-2725 2850);
DISPLAY INVISIBLE (-2725 2850);
FORCEPROP 1 LAST PATH I158
J 0
(-3050 2975);
DISPLAY 0.936170 (-3050 2975);
PAINT GREEN (-3050 2975);
DISPLAY INVISIBLE (-3050 2975);
FORCEADD TAP..6
(-3050 2925);
FORCEPROP 3 LASTPIN (-3000 2925) SIG_NAME M_F_CS_N<2>
J 0
(-2990 2935);
DISPLAY 0.659574 (-2990 2935);
PAINT MONO (-2990 2935);
DISPLAY INVISIBLE (-2990 2935);
FORCEPROP 1 LASTPIN (-3000 2925) BN 2
J 0
(-3050 2935);
DISPLAY 0.617021 (-3050 2935);
PAINT PINK (-3050 2935);
FORCEPROP 2 LAST CDS_LIB mstr_standard
J 0
(-3050 2925);
DISPLAY 0.787234 (-3050 2925);
PAINT MONO (-3050 2925);
DISPLAY INVISIBLE (-3050 2925);
FORCEPROP 1 LAST BODY_TYPE PLUMBING
J 0
(-3050 2875);
DISPLAY 1.234043 (-3050 2875);
PAINT GREEN (-3050 2875);
DISPLAY INVISIBLE (-3050 2875);
FORCEPROP 1 LAST HDL_TAP TRUE
J 0
(-2725 2800);
DISPLAY 1.234043 (-2725 2800);
PAINT GREEN (-2725 2800);
DISPLAY INVISIBLE (-2725 2800);
FORCEPROP 1 LAST PATH I159
J 0
(-3050 2925);
DISPLAY 0.936170 (-3050 2925);
PAINT GREEN (-3050 2925);
DISPLAY INVISIBLE (-3050 2925);
FORCEADD TAP..6
(-3050 2875);
FORCEPROP 3 LASTPIN (-3000 2875) SIG_NAME M_F_CS_N<1>
J 0
(-2990 2885);
DISPLAY 0.659574 (-2990 2885);
PAINT MONO (-2990 2885);
DISPLAY INVISIBLE (-2990 2885);
FORCEPROP 1 LASTPIN (-3000 2875) BN 1
J 0
(-3050 2885);
DISPLAY 0.617021 (-3050 2885);
PAINT PINK (-3050 2885);
FORCEPROP 2 LAST CDS_LIB mstr_standard
J 0
(-3050 2875);
DISPLAY 0.787234 (-3050 2875);
PAINT MONO (-3050 2875);
DISPLAY INVISIBLE (-3050 2875);
FORCEPROP 1 LAST BODY_TYPE PLUMBING
J 0
(-3050 2825);
DISPLAY 1.234043 (-3050 2825);
PAINT GREEN (-3050 2825);
DISPLAY INVISIBLE (-3050 2825);
FORCEPROP 1 LAST HDL_TAP TRUE
J 0
(-2725 2750);
DISPLAY 1.234043 (-2725 2750);
PAINT GREEN (-2725 2750);
DISPLAY INVISIBLE (-2725 2750);
FORCEPROP 1 LAST PATH I160
J 0
(-3050 2875);
DISPLAY 0.936170 (-3050 2875);
PAINT GREEN (-3050 2875);
DISPLAY INVISIBLE (-3050 2875);
FORCEADD TAP..6
(-3050 2825);
FORCEPROP 3 LASTPIN (-3000 2825) SIG_NAME M_F_CS_N<0>
J 0
(-2990 2835);
DISPLAY 0.659574 (-2990 2835);
PAINT MONO (-2990 2835);
DISPLAY INVISIBLE (-2990 2835);
FORCEPROP 1 LASTPIN (-3000 2825) BN 0
J 0
(-3050 2835);
DISPLAY 0.617021 (-3050 2835);
PAINT PINK (-3050 2835);
FORCEPROP 2 LAST CDS_LIB mstr_standard
J 0
(-3050 2825);
DISPLAY 0.787234 (-3050 2825);
PAINT MONO (-3050 2825);
DISPLAY INVISIBLE (-3050 2825);
FORCEPROP 1 LAST BODY_TYPE PLUMBING
J 0
(-3050 2775);
DISPLAY 1.234043 (-3050 2775);
PAINT GREEN (-3050 2775);
DISPLAY INVISIBLE (-3050 2775);
FORCEPROP 1 LAST HDL_TAP TRUE
J 0
(-2725 2700);
DISPLAY 1.234043 (-2725 2700);
PAINT GREEN (-2725 2700);
DISPLAY INVISIBLE (-2725 2700);
FORCEPROP 1 LAST PATH I161
J 0
(-3050 2825);
DISPLAY 0.936170 (-3050 2825);
PAINT GREEN (-3050 2825);
DISPLAY INVISIBLE (-3050 2825);
FORCEADD TAP..6
(-3050 2725);
FORCEPROP 3 LASTPIN (-3000 2725) SIG_NAME M_F_CKE<1>
J 0
(-2990 2735);
DISPLAY 0.659574 (-2990 2735);
PAINT MONO (-2990 2735);
DISPLAY INVISIBLE (-2990 2735);
FORCEPROP 1 LASTPIN (-3000 2725) BN 1
J 0
(-3050 2735);
DISPLAY 0.617021 (-3050 2735);
PAINT PINK (-3050 2735);
FORCEPROP 2 LAST CDS_LIB mstr_standard
J 0
(-3050 2725);
DISPLAY 0.787234 (-3050 2725);
PAINT MONO (-3050 2725);
DISPLAY INVISIBLE (-3050 2725);
FORCEPROP 1 LAST BODY_TYPE PLUMBING
J 0
(-3050 2675);
DISPLAY 1.234043 (-3050 2675);
PAINT GREEN (-3050 2675);
DISPLAY INVISIBLE (-3050 2675);
FORCEPROP 1 LAST HDL_TAP TRUE
J 0
(-2725 2600);
DISPLAY 1.234043 (-2725 2600);
PAINT GREEN (-2725 2600);
DISPLAY INVISIBLE (-2725 2600);
FORCEPROP 1 LAST PATH I162
J 0
(-3050 2725);
DISPLAY 0.936170 (-3050 2725);
PAINT GREEN (-3050 2725);
DISPLAY INVISIBLE (-3050 2725);
FORCEADD TAP..6
(-3050 2675);
FORCEPROP 3 LASTPIN (-3000 2675) SIG_NAME M_F_CKE<0>
J 0
(-2990 2685);
DISPLAY 0.659574 (-2990 2685);
PAINT MONO (-2990 2685);
DISPLAY INVISIBLE (-2990 2685);
FORCEPROP 1 LASTPIN (-3000 2675) BN 0
J 0
(-3050 2685);
DISPLAY 0.617021 (-3050 2685);
PAINT PINK (-3050 2685);
FORCEPROP 2 LAST CDS_LIB mstr_standard
J 0
(-3050 2675);
DISPLAY 0.787234 (-3050 2675);
PAINT MONO (-3050 2675);
DISPLAY INVISIBLE (-3050 2675);
FORCEPROP 1 LAST BODY_TYPE PLUMBING
J 0
(-3050 2625);
DISPLAY 1.234043 (-3050 2625);
PAINT GREEN (-3050 2625);
DISPLAY INVISIBLE (-3050 2625);
FORCEPROP 1 LAST HDL_TAP TRUE
J 0
(-2725 2550);
DISPLAY 1.234043 (-2725 2550);
PAINT GREEN (-2725 2550);
DISPLAY INVISIBLE (-2725 2550);
FORCEPROP 1 LAST PATH I163
J 0
(-3050 2675);
DISPLAY 0.936170 (-3050 2675);
PAINT GREEN (-3050 2675);
DISPLAY INVISIBLE (-3050 2675);
FORCEADD TAP..6
(-3050 2575);
FORCEPROP 3 LASTPIN (-3000 2575) SIG_NAME M_F_ODT<1>
J 0
(-2990 2585);
DISPLAY 0.659574 (-2990 2585);
PAINT MONO (-2990 2585);
DISPLAY INVISIBLE (-2990 2585);
FORCEPROP 1 LASTPIN (-3000 2575) BN 1
J 0
(-3050 2585);
DISPLAY 0.617021 (-3050 2585);
PAINT PINK (-3050 2585);
FORCEPROP 2 LAST CDS_LIB mstr_standard
J 0
(-3050 2575);
DISPLAY 0.787234 (-3050 2575);
PAINT MONO (-3050 2575);
DISPLAY INVISIBLE (-3050 2575);
FORCEPROP 1 LAST BODY_TYPE PLUMBING
J 0
(-3050 2525);
DISPLAY 1.234043 (-3050 2525);
PAINT GREEN (-3050 2525);
DISPLAY INVISIBLE (-3050 2525);
FORCEPROP 1 LAST HDL_TAP TRUE
J 0
(-2725 2450);
DISPLAY 1.234043 (-2725 2450);
PAINT GREEN (-2725 2450);
DISPLAY INVISIBLE (-2725 2450);
FORCEPROP 1 LAST PATH I164
J 0
(-3050 2575);
DISPLAY 0.936170 (-3050 2575);
PAINT GREEN (-3050 2575);
DISPLAY INVISIBLE (-3050 2575);
FORCEADD TAP..6
(-3050 2525);
FORCEPROP 3 LASTPIN (-3000 2525) SIG_NAME M_F_ODT<0>
J 0
(-2990 2535);
DISPLAY 0.659574 (-2990 2535);
PAINT MONO (-2990 2535);
DISPLAY INVISIBLE (-2990 2535);
FORCEPROP 1 LASTPIN (-3000 2525) BN 0
J 0
(-3050 2535);
DISPLAY 0.617021 (-3050 2535);
PAINT PINK (-3050 2535);
FORCEPROP 2 LAST CDS_LIB mstr_standard
J 0
(-3050 2525);
DISPLAY 0.787234 (-3050 2525);
PAINT MONO (-3050 2525);
DISPLAY INVISIBLE (-3050 2525);
FORCEPROP 1 LAST BODY_TYPE PLUMBING
J 0
(-3050 2475);
DISPLAY 1.234043 (-3050 2475);
PAINT GREEN (-3050 2475);
DISPLAY INVISIBLE (-3050 2475);
FORCEPROP 1 LAST HDL_TAP TRUE
J 0
(-2725 2400);
DISPLAY 1.234043 (-2725 2400);
PAINT GREEN (-2725 2400);
DISPLAY INVISIBLE (-2725 2400);
FORCEPROP 1 LAST PATH I165
J 0
(-3050 2525);
DISPLAY 0.936170 (-3050 2525);
PAINT GREEN (-3050 2525);
DISPLAY INVISIBLE (-3050 2525);
FORCEADD OFFPAGE..1
(-3700 3025);
FORCEPROP 2 LAST $XR0 28 
J 0
(-3921 3025);
DISPLAY 0.638298 (-3921 3025);
PAINT MONO (-3921 3025);
FORCEPROP 2 LAST $XR1 54 
J 0
(-4011 3025);
DISPLAY 0.638298 (-4011 3025);
PAINT MONO (-4011 3025);
FORCEPROP 2 LAST CDS_LIB mstr_standard
J 0
(-3700 3025);
DISPLAY 0.787234 (-3700 3025);
PAINT MONO (-3700 3025);
DISPLAY INVISIBLE (-3700 3025);
FORCEPROP 1 LAST OFFPAGE TRUE
J 0
(-3375 2900);
DISPLAY 0.936170 (-3375 2900);
PAINT GREEN (-3375 2900);
DISPLAY INVISIBLE (-3375 2900);
FORCEPROP 1 LAST COMMENT_BODY TRUE
J 0
(-3575 2925);
DISPLAY 0.936170 (-3575 2925);
PAINT GREEN (-3575 2925);
DISPLAY INVISIBLE (-3575 2925);
FORCEPROP 2 LAST PATH I166
J 0
(-3650 3100);
DISPLAY 0.787234 (-3650 3100);
PAINT MONO (-3650 3100);
DISPLAY INVISIBLE (-3650 3100);
FORCEADD OFFPAGE..1
(-3700 2775);
FORCEPROP 2 LAST $XR0 28 
J 0
(-3921 2775);
DISPLAY 0.638298 (-3921 2775);
PAINT MONO (-3921 2775);
FORCEPROP 2 LAST $XR1 54 
J 0
(-4011 2775);
DISPLAY 0.638298 (-4011 2775);
PAINT MONO (-4011 2775);
FORCEPROP 2 LAST CDS_LIB mstr_standard
J 0
(-3700 2775);
DISPLAY 0.787234 (-3700 2775);
PAINT MONO (-3700 2775);
DISPLAY INVISIBLE (-3700 2775);
FORCEPROP 1 LAST OFFPAGE TRUE
J 0
(-3375 2650);
DISPLAY 0.936170 (-3375 2650);
PAINT GREEN (-3375 2650);
DISPLAY INVISIBLE (-3375 2650);
FORCEPROP 1 LAST COMMENT_BODY TRUE
J 0
(-3575 2675);
DISPLAY 0.936170 (-3575 2675);
PAINT GREEN (-3575 2675);
DISPLAY INVISIBLE (-3575 2675);
FORCEPROP 2 LAST PATH I167
J 0
(-3650 2850);
DISPLAY 0.787234 (-3650 2850);
PAINT MONO (-3650 2850);
DISPLAY INVISIBLE (-3650 2850);
FORCEADD OFFPAGE..1
(-3700 2625);
FORCEPROP 2 LAST $XR0 28 
J 0
(-3921 2625);
DISPLAY 0.638298 (-3921 2625);
PAINT MONO (-3921 2625);
FORCEPROP 2 LAST $XR1 54 
J 0
(-4011 2625);
DISPLAY 0.638298 (-4011 2625);
PAINT MONO (-4011 2625);
FORCEPROP 2 LAST CDS_LIB mstr_standard
J 0
(-3700 2625);
DISPLAY 0.787234 (-3700 2625);
PAINT MONO (-3700 2625);
DISPLAY INVISIBLE (-3700 2625);
FORCEPROP 1 LAST OFFPAGE TRUE
J 0
(-3375 2500);
DISPLAY 0.936170 (-3375 2500);
PAINT GREEN (-3375 2500);
DISPLAY INVISIBLE (-3375 2500);
FORCEPROP 1 LAST COMMENT_BODY TRUE
J 0
(-3575 2525);
DISPLAY 0.936170 (-3575 2525);
PAINT GREEN (-3575 2525);
DISPLAY INVISIBLE (-3575 2525);
FORCEPROP 2 LAST PATH I168
J 0
(-3650 2700);
DISPLAY 0.787234 (-3650 2700);
PAINT MONO (-3650 2700);
DISPLAY INVISIBLE (-3650 2700);
FORCEADD OFFPAGE..1
(-3700 1425);
FORCEPROP 2 LAST $XR0 99 
J 0
(-3981 1425);
DISPLAY 0.638298 (-3981 1425);
PAINT MONO (-3981 1425);
FORCEPROP 2 LAST $XR1 49 
J 0
(-4071 1425);
DISPLAY 0.638298 (-4071 1425);
PAINT MONO (-4071 1425);
FORCEPROP 2 LAST $XR2 50 
J 0
(-4161 1425);
DISPLAY 0.638298 (-4161 1425);
PAINT MONO (-4161 1425);
FORCEPROP 2 LAST $XR3 51 
J 0
(-4251 1425);
DISPLAY 0.638298 (-4251 1425);
PAINT MONO (-4251 1425);
FORCEPROP 2 LAST $XR4 52 
J 0
(-4341 1425);
DISPLAY 0.638298 (-4341 1425);
PAINT MONO (-4341 1425);
FORCEPROP 2 LAST $XR5 54 
J 0
(-4431 1425);
DISPLAY 0.638298 (-4431 1425);
PAINT MONO (-4431 1425);
FORCEPROP 2 LAST CDS_LIB mstr_standard
J 0
(-3700 1425);
DISPLAY 0.787234 (-3700 1425);
PAINT MONO (-3700 1425);
DISPLAY INVISIBLE (-3700 1425);
FORCEPROP 1 LAST OFFPAGE TRUE
J 0
(-3375 1300);
DISPLAY 0.936170 (-3375 1300);
PAINT GREEN (-3375 1300);
DISPLAY INVISIBLE (-3375 1300);
FORCEPROP 1 LAST COMMENT_BODY TRUE
J 0
(-3575 1325);
DISPLAY 0.936170 (-3575 1325);
PAINT GREEN (-3575 1325);
DISPLAY INVISIBLE (-3575 1325);
FORCEPROP 2 LAST PATH I169
J 0
(-3650 1500);
DISPLAY 0.787234 (-3650 1500);
PAINT MONO (-3650 1500);
DISPLAY INVISIBLE (-3650 1500);
FORCEADD PVTT_DEF..1
(-1100 2750);
FORCEPROP 3 LASTPIN (-1100 2700) SIG_NAME PVTT_DEF\g
J 0
(-1090 2710);
DISPLAY 0.659574 (-1090 2710);
PAINT MONO (-1090 2710);
DISPLAY INVISIBLE (-1090 2710);
FORCEPROP 1 LAST VOLTAGE 0.6V
J 0
(-1145 2707);
DISPLAY 0.340426 (-1145 2707);
PAINT SKYBLUE (-1145 2707);
DISPLAY INVISIBLE (-1145 2707);
FORCEPROP 2 LAST BOM_COST MEM
J 0
(-1100 2755);
PAINT ORANGE (-1100 2755);
DISPLAY INVISIBLE (-1100 2755);
FORCEPROP 2 LAST CDS_LIB mstr_symbols
J 0
(-1100 2750);
PAINT ORANGE (-1100 2750);
DISPLAY INVISIBLE (-1100 2750);
FORCEPROP 1 LAST BODY_TYPE PLUMBING
J 0
(-1145 2707);
DISPLAY 0.340426 (-1145 2707);
PAINT GREEN (-1145 2707);
DISPLAY INVISIBLE (-1145 2707);
FORCEPROP 1 LAST PATH I17
J 0
(-1050 2775);
DISPLAY 0.872340 (-1050 2775);
PAINT AQUA (-1050 2775);
DISPLAY INVISIBLE (-1050 2775);
FORCEPROP 2 LAST ROOM DDR4_CH_C
J 0
(-1100 2850);
DISPLAY 0.787234 (-1100 2850);
PAINT ORANGE (-1100 2850);
DISPLAY INVISIBLE (-1100 2850);
FORCEPROP 1 LAST HDL_POWER PVTT_DEF
J 1
(-1100 2800);
DISPLAY 0.872340 (-1100 2800);
PAINT GREEN (-1100 2800);
DISPLAY INVISIBLE (-1100 2800);
FORCEADD OFFPAGE..6
(-3700 1475);
FORCEPROP 2 LAST $XR0 49 
J 0
(-3979 1475);
DISPLAY 0.638298 (-3979 1475);
PAINT MONO (-3979 1475);
FORCEPROP 2 LAST $XR1 50 
J 0
(-4069 1475);
DISPLAY 0.638298 (-4069 1475);
PAINT MONO (-4069 1475);
FORCEPROP 2 LAST $XR2 51 
J 0
(-4159 1475);
DISPLAY 0.638298 (-4159 1475);
PAINT MONO (-4159 1475);
FORCEPROP 2 LAST $XR3 52 
J 0
(-4249 1475);
DISPLAY 0.638298 (-4249 1475);
PAINT MONO (-4249 1475);
FORCEPROP 2 LAST $XR4 54 
J 0
(-4339 1475);
DISPLAY 0.638298 (-4339 1475);
PAINT MONO (-4339 1475);
FORCEPROP 2 LAST $XR5 99 
J 0
(-4429 1475);
DISPLAY 0.638298 (-4429 1475);
PAINT MONO (-4429 1475);
FORCEPROP 2 LAST CDS_LIB mstr_standard
J 0
(-3700 1475);
DISPLAY 0.787234 (-3700 1475);
PAINT MONO (-3700 1475);
DISPLAY INVISIBLE (-3700 1475);
FORCEPROP 1 LAST OFFPAGE TRUE
J 0
(-3375 1350);
DISPLAY 0.936170 (-3375 1350);
PAINT GREEN (-3375 1350);
DISPLAY INVISIBLE (-3375 1350);
FORCEPROP 1 LAST COMMENT_BODY TRUE
J 0
(-3600 1400);
DISPLAY 0.936170 (-3600 1400);
PAINT GREEN (-3600 1400);
DISPLAY INVISIBLE (-3600 1400);
FORCEPROP 2 LAST PATH I170
J 0
(-3650 1550);
DISPLAY 0.787234 (-3650 1550);
PAINT MONO (-3650 1550);
DISPLAY INVISIBLE (-3650 1550);
FORCEADD SCONN288_H44441004..4
(-250 2050);
FORCEPROP 1 LAST LOCATION J4A1
J 0
(-700 3150);
DISPLAY 0.617021 (-700 3150);
PAINT AQUA (-700 3150);
FORCEPROP 1 LAST PART_NUMBER H44441-004
J 0
(-700 1000);
DISPLAY 0.617021 (-700 1000);
PAINT BLUE (-700 1000);
FORCEPROP 1 LAST MATERIAL SCONN
J 0
(-700 3100);
DISPLAY 0.617021 (-700 3100);
PAINT SKYBLUE (-700 3100);
FORCEPROP 2 LASTPIN (-750 2600) $PN 77
J 2
(-760 2610);
DISPLAY 0.617021 (-760 2610);
PAINT ORANGE (-760 2610);
FORCEPROP 2 LASTPIN (-750 2550) $PN 221
J 2
(-760 2560);
DISPLAY 0.617021 (-760 2560);
PAINT ORANGE (-760 2560);
FORCEPROP 2 LASTPIN (-750 2900) $PN 142
J 2
(-760 2910);
DISPLAY 0.617021 (-760 2910);
PAINT ORANGE (-760 2910);
FORCEPROP 2 LASTPIN (-750 2850) $PN 143
J 2
(-760 2860);
DISPLAY 0.617021 (-760 2860);
PAINT ORANGE (-760 2860);
FORCEPROP 2 LASTPIN (-750 2800) $PN 288
J 2
(-760 2810);
DISPLAY 0.617021 (-760 2810);
PAINT ORANGE (-760 2810);
FORCEPROP 2 LASTPIN (-750 2750) $PN 286
J 2
(-760 2760);
DISPLAY 0.617021 (-760 2760);
PAINT ORANGE (-760 2760);
FORCEPROP 2 LASTPIN (-750 2700) $PN 287
J 2
(-760 2710);
DISPLAY 0.617021 (-760 2710);
PAINT ORANGE (-760 2710);
FORCEPROP 2 LASTPIN (-750 2450) $PN 59
J 2
(-760 2460);
DISPLAY 0.617021 (-760 2460);
PAINT ORANGE (-760 2460);
FORCEPROP 2 LASTPIN (-750 2400) $PN 61
J 2
(-760 2410);
DISPLAY 0.617021 (-760 2410);
PAINT ORANGE (-760 2410);
FORCEPROP 2 LASTPIN (-750 2350) $PN 64
J 2
(-760 2360);
DISPLAY 0.617021 (-760 2360);
PAINT ORANGE (-760 2360);
FORCEPROP 2 LASTPIN (-750 2300) $PN 67
J 2
(-760 2310);
DISPLAY 0.617021 (-760 2310);
PAINT ORANGE (-760 2310);
FORCEPROP 2 LASTPIN (-750 2250) $PN 70
J 2
(-760 2260);
DISPLAY 0.617021 (-760 2260);
PAINT ORANGE (-760 2260);
FORCEPROP 2 LASTPIN (-750 2200) $PN 73
J 2
(-760 2210);
DISPLAY 0.617021 (-760 2210);
PAINT ORANGE (-760 2210);
FORCEPROP 2 LASTPIN (-750 2150) $PN 76
J 2
(-760 2160);
DISPLAY 0.617021 (-760 2160);
PAINT ORANGE (-760 2160);
FORCEPROP 2 LASTPIN (-750 2100) $PN 80
J 2
(-760 2110);
DISPLAY 0.617021 (-760 2110);
PAINT ORANGE (-760 2110);
FORCEPROP 2 LASTPIN (-750 2050) $PN 83
J 2
(-760 2060);
DISPLAY 0.617021 (-760 2060);
PAINT ORANGE (-760 2060);
FORCEPROP 2 LASTPIN (-750 2000) $PN 85
J 2
(-760 2010);
DISPLAY 0.617021 (-760 2010);
PAINT ORANGE (-760 2010);
FORCEPROP 2 LASTPIN (-750 1950) $PN 88
J 2
(-760 1960);
DISPLAY 0.617021 (-760 1960);
PAINT ORANGE (-760 1960);
FORCEPROP 2 LASTPIN (-750 1900) $PN 90
J 2
(-760 1910);
DISPLAY 0.617021 (-760 1910);
PAINT ORANGE (-760 1910);
FORCEPROP 2 LASTPIN (-750 1850) $PN 92
J 2
(-760 1860);
DISPLAY 0.617021 (-760 1860);
PAINT ORANGE (-760 1860);
FORCEPROP 2 LASTPIN (-750 1800) $PN 204
J 2
(-760 1810);
DISPLAY 0.617021 (-760 1810);
PAINT ORANGE (-760 1810);
FORCEPROP 2 LASTPIN (-750 1750) $PN 206
J 2
(-760 1760);
DISPLAY 0.617021 (-760 1760);
PAINT ORANGE (-760 1760);
FORCEPROP 2 LASTPIN (-750 1700) $PN 209
J 2
(-760 1710);
DISPLAY 0.617021 (-760 1710);
PAINT ORANGE (-760 1710);
FORCEPROP 2 LASTPIN (-750 1650) $PN 212
J 2
(-760 1660);
DISPLAY 0.617021 (-760 1660);
PAINT ORANGE (-760 1660);
FORCEPROP 2 LASTPIN (-750 1600) $PN 215
J 2
(-760 1610);
DISPLAY 0.617021 (-760 1610);
PAINT ORANGE (-760 1610);
FORCEPROP 2 LASTPIN (-750 1550) $PN 217
J 2
(-760 1560);
DISPLAY 0.617021 (-760 1560);
PAINT ORANGE (-760 1560);
FORCEPROP 2 LASTPIN (-750 1500) $PN 220
J 2
(-760 1510);
DISPLAY 0.617021 (-760 1510);
PAINT ORANGE (-760 1510);
FORCEPROP 2 LASTPIN (-750 1450) $PN 223
J 2
(-760 1460);
DISPLAY 0.617021 (-760 1460);
PAINT ORANGE (-760 1460);
FORCEPROP 2 LASTPIN (-750 1400) $PN 226
J 2
(-760 1410);
DISPLAY 0.617021 (-760 1410);
PAINT ORANGE (-760 1410);
FORCEPROP 2 LASTPIN (-750 1350) $PN 229
J 2
(-760 1360);
DISPLAY 0.617021 (-760 1360);
PAINT ORANGE (-760 1360);
FORCEPROP 2 LASTPIN (-750 1300) $PN 231
J 2
(-760 1310);
DISPLAY 0.617021 (-760 1310);
PAINT ORANGE (-760 1310);
FORCEPROP 2 LASTPIN (-750 1250) $PN 233
J 2
(-760 1260);
DISPLAY 0.617021 (-760 1260);
PAINT ORANGE (-760 1260);
FORCEPROP 2 LASTPIN (-750 1200) $PN 236
J 2
(-760 1210);
DISPLAY 0.617021 (-760 1210);
PAINT ORANGE (-760 1210);
FORCEPROP 2 LASTPIN (250 2900) $PN 1
J 0
(260 2910);
DISPLAY 0.617021 (260 2910);
PAINT ORANGE (260 2910);
FORCEPROP 2 LASTPIN (250 2850) $PN 145
J 0
(260 2860);
DISPLAY 0.617021 (260 2860);
PAINT ORANGE (260 2860);
FORCEPROP 1 LAST PACK_TYPE PIP
J 0
(-700 3200);
PAINT SKYBLUE (-700 3200);
DISPLAY INVISIBLE (-700 3200);
FORCEPROP 2 LAST BOM_COST MEM
J 0
(-250 2050);
PAINT ORANGE (-250 2050);
DISPLAY INVISIBLE (-250 2050);
FORCEPROP 2 LAST CDS_LIB mstr_sconn
J 0
(-250 2050);
PAINT ORANGE (-250 2050);
DISPLAY INVISIBLE (-250 2050);
FORCEPROP 2 LAST SEC_TYPE PIP
J 0
(-700 3200);
DISPLAY 1.021277 (-700 3200);
PAINT ORANGE (-700 3200);
DISPLAY INVISIBLE (-700 3200);
FORCEPROP 2 LAST SEC 4
J 0
(-700 3200);
DISPLAY 0.680851 (-700 3200);
PAINT MONO (-700 3200);
DISPLAY INVISIBLE (-700 3200);
FORCEPROP 2 LAST CDS_LOCATION J4A1
J 0
(-700 3150);
DISPLAY 0.617021 (-700 3150);
PAINT AQUA (-700 3150);
DISPLAY INVISIBLE (-700 3150);
FORCEPROP 1 LAST PATH I171
J 0
(-250 3100);
PAINT GREEN (-250 3100);
DISPLAY INVISIBLE (-250 3100);
FORCEPROP 2 LAST ROOM DDR4_CH_F
J 0
(-250 2050);
PAINT ORANGE (-250 2050);
DISPLAY INVISIBLE (-250 2050);
FORCEADD PVDDQ_DEF..1
(-1275 2600);
FORCEPROP 3 LASTPIN (-1275 2550) SIG_NAME PVDDQ_DEF\g
J 0
(-1265 2560);
DISPLAY 0.659574 (-1265 2560);
PAINT MONO (-1265 2560);
DISPLAY INVISIBLE (-1265 2560);
FORCEPROP 1 LAST VOLTAGE 1.2V
J 0
(-1320 2557);
DISPLAY 0.340426 (-1320 2557);
PAINT SKYBLUE (-1320 2557);
DISPLAY INVISIBLE (-1320 2557);
FORCEPROP 2 LAST BOM_COST MEM
J 0
(-1275 2605);
PAINT ORANGE (-1275 2605);
DISPLAY INVISIBLE (-1275 2605);
FORCEPROP 2 LAST CDS_LIB mstr_symbols
J 0
(-1275 2600);
PAINT ORANGE (-1275 2600);
DISPLAY INVISIBLE (-1275 2600);
FORCEPROP 1 LAST BODY_TYPE PLUMBING
J 0
(-1320 2557);
DISPLAY 0.340426 (-1320 2557);
PAINT GREEN (-1320 2557);
DISPLAY INVISIBLE (-1320 2557);
FORCEPROP 1 LAST PATH I172
J 0
(-1225 2625);
DISPLAY 0.872340 (-1225 2625);
PAINT AQUA (-1225 2625);
DISPLAY INVISIBLE (-1225 2625);
FORCEPROP 2 LAST ROOM DDR4_CH_C
J 0
(-1275 2700);
DISPLAY 0.787234 (-1275 2700);
PAINT ORANGE (-1275 2700);
DISPLAY INVISIBLE (-1275 2700);
FORCEPROP 1 LAST HDL_POWER PVDDQ_DEF
J 1
(-1275 2650);
DISPLAY 0.872340 (-1275 2650);
PAINT GREEN (-1275 2650);
DISPLAY INVISIBLE (-1275 2650);
FORCEADD GND..1
R 2
(2450 1100);
FORCEPROP 3 LASTPIN (2450 1150) SIG_NAME GND\g
J 0
(2460 1160);
DISPLAY 0.659574 (2460 1160);
PAINT MONO (2460 1160);
DISPLAY INVISIBLE (2460 1160);
FORCEPROP 1 LAST VOLTAGE 0
J 0
(2450 1100);
PAINT SKYBLUE (2450 1100);
DISPLAY INVISIBLE (2450 1100);
FORCEPROP 2 LAST BOM_COST MEM
J 0
(2450 1105);
PAINT ORANGE (2450 1105);
DISPLAY INVISIBLE (2450 1105);
FORCEPROP 1 LAST SIZE 1B
J 2
(2375 1050);
DISPLAY 1.170213 (2375 1050);
PAINT GREEN (2375 1050);
DISPLAY INVISIBLE (2375 1050);
FORCEPROP 2 LAST CDS_LIB mstr_symbols
J 0
(2450 1100);
DISPLAY 0.787234 (2450 1100);
PAINT MONO (2450 1100);
DISPLAY INVISIBLE (2450 1100);
FORCEPROP 1 LAST BODY_TYPE PLUMBING
J 2
(2495 1057);
DISPLAY 0.340426 (2495 1057);
PAINT GREEN (2495 1057);
DISPLAY INVISIBLE (2495 1057);
FORCEPROP 1 LAST PATH I173
J 2
(2375 1100);
DISPLAY 1.404255 (2375 1100);
PAINT GREEN (2375 1100);
DISPLAY INVISIBLE (2375 1100);
FORCEPROP 2 LAST ROOM DDR4_CH_C
J 0
(2450 1105);
PAINT ORANGE (2450 1105);
DISPLAY INVISIBLE (2450 1105);
FORCEPROP 1 LAST HDL_POWER GND
J 2
(2450 1250);
DISPLAY 0.553191 (2450 1250);
PAINT GREEN (2450 1250);
DISPLAY INVISIBLE (2450 1250);
FORCEADD GND..1
R 2
(-5050 1475);
FORCEPROP 3 LASTPIN (-5050 1525) SIG_NAME GND\g
J 0
(-5040 1535);
DISPLAY 0.659574 (-5040 1535);
PAINT MONO (-5040 1535);
DISPLAY INVISIBLE (-5040 1535);
FORCEPROP 1 LAST VOLTAGE 0
J 0
(-5050 1475);
PAINT SKYBLUE (-5050 1475);
DISPLAY INVISIBLE (-5050 1475);
FORCEPROP 2 LAST BOM_COST MEM
J 0
(-5050 1480);
PAINT ORANGE (-5050 1480);
DISPLAY INVISIBLE (-5050 1480);
FORCEPROP 2 LAST CDS_LIB mstr_symbols
J 0
(-5050 1475);
DISPLAY 0.787234 (-5050 1475);
PAINT MONO (-5050 1475);
DISPLAY INVISIBLE (-5050 1475);
FORCEPROP 1 LAST SIZE 1B
J 2
(-5125 1425);
DISPLAY 1.170213 (-5125 1425);
PAINT GREEN (-5125 1425);
DISPLAY INVISIBLE (-5125 1425);
FORCEPROP 1 LAST BODY_TYPE PLUMBING
J 2
(-5005 1432);
DISPLAY 0.340426 (-5005 1432);
PAINT GREEN (-5005 1432);
DISPLAY INVISIBLE (-5005 1432);
FORCEPROP 1 LAST PATH I175
J 2
(-5125 1475);
DISPLAY 1.404255 (-5125 1475);
PAINT GREEN (-5125 1475);
DISPLAY INVISIBLE (-5125 1475);
FORCEPROP 2 LAST ROOM DDR4_CH_C
J 0
(-5050 1480);
PAINT ORANGE (-5050 1480);
DISPLAY INVISIBLE (-5050 1480);
FORCEPROP 1 LAST HDL_POWER GND
J 2
(-5050 1625);
DISPLAY 0.553191 (-5050 1625);
PAINT GREEN (-5050 1625);
DISPLAY INVISIBLE (-5050 1625);
FORCEADD OFFPAGE..5
(-4025 2125);
FORCEPROP 2 LAST $XR0 43 
J 0
(-4249 2125);
DISPLAY 0.638298 (-4249 2125);
PAINT MONO (-4249 2125);
FORCEPROP 2 LAST $XR1 44 
J 0
(-4339 2125);
DISPLAY 0.638298 (-4339 2125);
PAINT MONO (-4339 2125);
FORCEPROP 2 LAST $XR2 45 
J 0
(-4429 2125);
DISPLAY 0.638298 (-4429 2125);
PAINT MONO (-4429 2125);
FORCEPROP 2 LAST $XR3 46 
J 0
(-4519 2125);
DISPLAY 0.638298 (-4519 2125);
PAINT MONO (-4519 2125);
FORCEPROP 2 LAST $XR4 47 
J 0
(-4609 2125);
DISPLAY 0.638298 (-4609 2125);
PAINT MONO (-4609 2125);
FORCEPROP 2 LAST $XR5 48 
J 0
(-4699 2125);
DISPLAY 0.638298 (-4699 2125);
PAINT MONO (-4699 2125);
FORCEPROP 2 LAST $XR6 49 
J 0
(-4789 2125);
DISPLAY 0.638298 (-4789 2125);
PAINT MONO (-4789 2125);
FORCEPROP 2 LAST $XR7 50 
J 0
(-4879 2125);
DISPLAY 0.638298 (-4879 2125);
PAINT MONO (-4879 2125);
FORCEPROP 2 LAST $XR8 51 
J 0
(-4969 2125);
DISPLAY 0.638298 (-4969 2125);
PAINT MONO (-4969 2125);
FORCEPROP 2 LAST $XR9 52 
J 0
(-5059 2125);
DISPLAY 0.638298 (-5059 2125);
PAINT MONO (-5059 2125);
FORCEPROP 2 LAST $XR10 54 
J 0
(-4249 2089);
DISPLAY 0.638298 (-4249 2089);
PAINT MONO (-4249 2089);
FORCEPROP 2 LAST $XR11 77 
J 0
(-4339 2089);
DISPLAY 0.638298 (-4339 2089);
PAINT MONO (-4339 2089);
FORCEPROP 2 LAST $XR12 78 
J 0
(-4429 2089);
DISPLAY 0.638298 (-4429 2089);
PAINT MONO (-4429 2089);
FORCEPROP 2 LAST $XR13 79 
J 0
(-4519 2089);
DISPLAY 0.638298 (-4519 2089);
PAINT MONO (-4519 2089);
FORCEPROP 2 LAST $XR14 80 
J 0
(-4609 2089);
DISPLAY 0.638298 (-4609 2089);
PAINT MONO (-4609 2089);
FORCEPROP 2 LAST $XR15 81 
J 0
(-4699 2089);
DISPLAY 0.638298 (-4699 2089);
PAINT MONO (-4699 2089);
FORCEPROP 2 LAST $XR16 82 
J 0
(-4789 2089);
DISPLAY 0.638298 (-4789 2089);
PAINT MONO (-4789 2089);
FORCEPROP 2 LAST $XR17 83 
J 0
(-4879 2089);
DISPLAY 0.638298 (-4879 2089);
PAINT MONO (-4879 2089);
FORCEPROP 2 LAST $XR18 84 
J 0
(-4969 2089);
DISPLAY 0.638298 (-4969 2089);
PAINT MONO (-4969 2089);
FORCEPROP 2 LAST $XR19 85 
J 0
(-5059 2089);
DISPLAY 0.638298 (-5059 2089);
PAINT MONO (-5059 2089);
FORCEPROP 2 LAST $XR20 86 
J 0
(-4249 2161);
DISPLAY 0.638298 (-4249 2161);
PAINT MONO (-4249 2161);
FORCEPROP 2 LAST $XR21 87 
J 0
(-4339 2161);
DISPLAY 0.638298 (-4339 2161);
PAINT MONO (-4339 2161);
FORCEPROP 2 LAST $XR22 88 
J 0
(-4429 2161);
DISPLAY 0.638298 (-4429 2161);
PAINT MONO (-4429 2161);
FORCEPROP 2 LAST $XR23 94 
J 0
(-4519 2161);
DISPLAY 0.638298 (-4519 2161);
PAINT MONO (-4519 2161);
FORCEPROP 2 LAST CDS_LIB mstr_standard
J 0
(-4025 2125);
DISPLAY 0.787234 (-4025 2125);
PAINT MONO (-4025 2125);
DISPLAY INVISIBLE (-4025 2125);
FORCEPROP 1 LAST OFFPAGE TRUE
J 0
(-3700 2000);
DISPLAY 1.404255 (-3700 2000);
PAINT GREEN (-3700 2000);
DISPLAY INVISIBLE (-3700 2000);
FORCEPROP 1 LAST COMMENT_BODY TRUE
J 0
(-3925 2050);
DISPLAY 1.404255 (-3925 2050);
PAINT GREEN (-3925 2050);
DISPLAY INVISIBLE (-3925 2050);
FORCEPROP 2 LAST PATH I176
J 0
(-3975 2200);
DISPLAY 0.787234 (-3975 2200);
PAINT ORANGE (-3975 2200);
DISPLAY INVISIBLE (-3975 2200);
FORCEADD OFFPAGE..1
(-4650 1325);
FORCEPROP 2 LAST $XR0 98 
J 0
(-4901 1325);
DISPLAY 0.638298 (-4901 1325);
PAINT MONO (-4901 1325);
FORCEPROP 2 LAST $XR1 54 
J 0
(-4991 1325);
DISPLAY 0.638298 (-4991 1325);
PAINT MONO (-4991 1325);
FORCEPROP 2 LAST CDS_LIB mstr_standard
J 0
(-4650 1325);
DISPLAY 0.787234 (-4650 1325);
PAINT MONO (-4650 1325);
DISPLAY INVISIBLE (-4650 1325);
FORCEPROP 1 LAST OFFPAGE TRUE
J 0
(-4325 1200);
DISPLAY 0.936170 (-4325 1200);
PAINT GREEN (-4325 1200);
DISPLAY INVISIBLE (-4325 1200);
FORCEPROP 1 LAST COMMENT_BODY TRUE
J 0
(-4525 1225);
DISPLAY 0.936170 (-4525 1225);
PAINT GREEN (-4525 1225);
DISPLAY INVISIBLE (-4525 1225);
FORCEPROP 2 LAST PATH I177
J 0
(-4900 1375);
DISPLAY 0.787234 (-4900 1375);
PAINT ORANGE (-4900 1375);
DISPLAY INVISIBLE (-4900 1375);
FORCEADD CAP_A..1
R 2
(-4500 1125);
FORCEPROP 1 LAST LOCATION C6L1
J 2
(-4550 1225);
DISPLAY 0.617021 (-4550 1225);
PAINT AQUA (-4550 1225);
FORCEPROP 1 LAST PART_NUMBER A36096-045
J 2
(-4550 975);
DISPLAY 0.617021 (-4550 975);
PAINT BLUE (-4550 975);
FORCEPROP 1 LAST VALUE 0.01UF
J 2
(-4550 1175);
DISPLAY 0.617021 (-4550 1175);
PAINT SKYBLUE (-4550 1175);
FORCEPROP 1 LAST TOLERANCE 10%
J 2
(-4550 1075);
DISPLAY 0.617021 (-4550 1075);
PAINT SKYBLUE (-4550 1075);
FORCEPROP 1 LAST PACK_TYPE 0402V
J 2
(-4550 925);
DISPLAY 0.617021 (-4550 925);
PAINT SKYBLUE (-4550 925);
FORCEPROP 1 LAST VOLTAGE 25V
J 2
(-4550 1125);
DISPLAY 0.617021 (-4550 1125);
PAINT SKYBLUE (-4550 1125);
FORCEPROP 1 LAST MATERIAL X7R
J 2
(-4550 1025);
DISPLAY 0.617021 (-4550 1025);
PAINT SKYBLUE (-4550 1025);
FORCEPROP 2 LAST CDS_LOCATION C6L1
J 2
(-4550 1225);
DISPLAY 0.617021 (-4550 1225);
PAINT AQUA (-4550 1225);
DISPLAY INVISIBLE (-4550 1225);
FORCEPROP 2 LAST BOM_COST MEM
J 0
(-4500 1125);
PAINT ORANGE (-4500 1125);
DISPLAY INVISIBLE (-4500 1125);
FORCEPROP 2 LAST CDS_LIB dev_discrete
J 0
(-4500 1125);
PAINT ORANGE (-4500 1125);
DISPLAY INVISIBLE (-4500 1125);
FORCEPROP 2 LAST CDS_SEC 1
J 2
(-4550 1325);
PAINT MONO (-4550 1325);
DISPLAY INVISIBLE (-4550 1325);
FORCEPROP 2 LAST $SEC 1
J 0
(-4550 1325);
PAINT MONO (-4550 1325);
DISPLAY INVISIBLE (-4550 1325);
FORCEPROP 1 LAST PATH I178
J 2
(-4550 1275);
DISPLAY 0.978723 (-4550 1275);
PAINT WHITE (-4550 1275);
DISPLAY INVISIBLE (-4550 1275);
FORCEPROP 2 LAST ROOM DDR4_CH_F
J 0
(-4500 1125);
PAINT ORANGE (-4500 1125);
DISPLAY INVISIBLE (-4500 1125);
FORCEPROP 1 LASTPIN (-4500 1225) $PN 1
J 2
(-4510 1205);
DISPLAY 0.787234 (-4510 1205);
PAINT ORANGE (-4510 1205);
DISPLAY INVISIBLE (-4510 1205);
FORCEPROP 1 LASTPIN (-4500 1025) $PN 2
J 2
(-4510 1005);
DISPLAY 0.787234 (-4510 1005);
PAINT ORANGE (-4510 1005);
DISPLAY INVISIBLE (-4510 1005);
FORCEADD GND..1
(-4500 875);
FORCEPROP 3 LASTPIN (-4500 925) SIG_NAME GND\g
J 0
(-4490 935);
DISPLAY 0.659574 (-4490 935);
PAINT MONO (-4490 935);
DISPLAY INVISIBLE (-4490 935);
FORCEPROP 1 LAST VOLTAGE 0
J 0
(-4500 875);
PAINT SKYBLUE (-4500 875);
DISPLAY INVISIBLE (-4500 875);
FORCEPROP 2 LAST BOM_COST MEM
J 0
(-4500 880);
PAINT ORANGE (-4500 880);
DISPLAY INVISIBLE (-4500 880);
FORCEPROP 1 LAST SIZE 1B
J 0
(-4425 825);
DISPLAY 1.787234 (-4425 825);
PAINT GREEN (-4425 825);
DISPLAY INVISIBLE (-4425 825);
FORCEPROP 2 LAST CDS_LIB mstr_symbols
J 0
(-4500 875);
PAINT ORANGE (-4500 875);
DISPLAY INVISIBLE (-4500 875);
FORCEPROP 1 LAST BODY_TYPE PLUMBING
J 0
(-4545 832);
DISPLAY 0.340426 (-4545 832);
PAINT GREEN (-4545 832);
DISPLAY INVISIBLE (-4545 832);
FORCEPROP 1 LAST PATH I179
J 0
(-4425 875);
DISPLAY 1.404255 (-4425 875);
PAINT GREEN (-4425 875);
DISPLAY INVISIBLE (-4425 875);
FORCEPROP 2 LAST ROOM DDR4_CH_C
J 0
(-4500 880);
PAINT ORANGE (-4500 880);
DISPLAY INVISIBLE (-4500 880);
FORCEPROP 1 LAST HDL_POWER GND
J 0
(-4500 1025);
DISPLAY 1.404255 (-4500 1025);
PAINT GREEN (-4500 1025);
DISPLAY INVISIBLE (-4500 1025);
FORCEADD PVPP_DEF..1
(-950 3050);
FORCEPROP 3 LASTPIN (-950 3000) SIG_NAME PVPP_DEF\g
J 0
(-940 3010);
DISPLAY 0.659574 (-940 3010);
PAINT MONO (-940 3010);
DISPLAY INVISIBLE (-940 3010);
FORCEPROP 1 LAST VOLTAGE 2.5V
J 0
(-995 3007);
DISPLAY 0.340426 (-995 3007);
PAINT SKYBLUE (-995 3007);
DISPLAY INVISIBLE (-995 3007);
FORCEPROP 0 LAST BOM_COST MEM
J 0
(-950 3150);
PAINT ORANGE (-950 3150);
DISPLAY INVISIBLE (-950 3150);
FORCEPROP 2 LAST CDS_LIB mstr_symbols
J 0
(-950 3050);
PAINT ORANGE (-950 3050);
DISPLAY INVISIBLE (-950 3050);
FORCEPROP 1 LAST BODY_TYPE PLUMBING
J 0
(-995 3007);
DISPLAY 0.340426 (-995 3007);
PAINT GREEN (-995 3007);
DISPLAY INVISIBLE (-995 3007);
FORCEPROP 1 LAST PATH I180
J 0
(-900 3075);
DISPLAY 0.872340 (-900 3075);
PAINT AQUA (-900 3075);
DISPLAY INVISIBLE (-900 3075);
FORCEPROP 2 LAST ROOM DDR4_CH_C
J 0
(-950 3150);
PAINT ORANGE (-950 3150);
DISPLAY INVISIBLE (-950 3150);
FORCEPROP 1 LAST HDL_POWER PVPP_DEF
J 1
(-950 3100);
DISPLAY 0.872340 (-950 3100);
PAINT GREEN (-950 3100);
DISPLAY INVISIBLE (-950 3100);
FORCEADD PVPP_DEF..1
(-5050 1825);
FORCEPROP 3 LASTPIN (-5050 1775) SIG_NAME PVPP_DEF\g
J 0
(-5040 1785);
DISPLAY 0.659574 (-5040 1785);
PAINT MONO (-5040 1785);
DISPLAY INVISIBLE (-5040 1785);
FORCEPROP 1 LAST VOLTAGE 2.5V
J 0
(-5095 1782);
DISPLAY 0.340426 (-5095 1782);
PAINT SKYBLUE (-5095 1782);
DISPLAY INVISIBLE (-5095 1782);
FORCEPROP 0 LAST BOM_COST MEM
J 0
(-5050 1925);
PAINT ORANGE (-5050 1925);
DISPLAY INVISIBLE (-5050 1925);
FORCEPROP 2 LAST CDS_LIB mstr_symbols
J 0
(-5050 1825);
PAINT ORANGE (-5050 1825);
DISPLAY INVISIBLE (-5050 1825);
FORCEPROP 1 LAST BODY_TYPE PLUMBING
J 0
(-5095 1782);
DISPLAY 0.340426 (-5095 1782);
PAINT GREEN (-5095 1782);
DISPLAY INVISIBLE (-5095 1782);
FORCEPROP 1 LAST PATH I181
J 0
(-5000 1850);
DISPLAY 0.872340 (-5000 1850);
PAINT AQUA (-5000 1850);
DISPLAY INVISIBLE (-5000 1850);
FORCEPROP 2 LAST ROOM DDR4_CH_C
J 0
(-5050 1925);
PAINT ORANGE (-5050 1925);
DISPLAY INVISIBLE (-5050 1925);
FORCEPROP 1 LAST HDL_POWER PVPP_DEF
J 1
(-5050 1875);
DISPLAY 0.872340 (-5050 1875);
PAINT GREEN (-5050 1875);
DISPLAY INVISIBLE (-5050 1875);
FORCEADD OFFPAGE..1
(-3700 1025);
FORCEPROP 2 LAST $XR0 89 
J 0
(-3921 1025);
DISPLAY 0.638298 (-3921 1025);
PAINT MONO (-3921 1025);
FORCEPROP 2 LAST $XR1 49 
J 0
(-4011 1025);
DISPLAY 0.638298 (-4011 1025);
PAINT MONO (-4011 1025);
FORCEPROP 2 LAST $XR2 50 
J 0
(-4101 1025);
DISPLAY 0.638298 (-4101 1025);
PAINT MONO (-4101 1025);
FORCEPROP 2 LAST $XR3 51 
J 0
(-4191 1025);
DISPLAY 0.638298 (-4191 1025);
PAINT MONO (-4191 1025);
FORCEPROP 2 LAST $XR4 52 
J 0
(-4281 1025);
DISPLAY 0.638298 (-4281 1025);
PAINT MONO (-4281 1025);
FORCEPROP 2 LAST $XR5 54 
J 0
(-4371 1025);
DISPLAY 0.638298 (-4371 1025);
PAINT MONO (-4371 1025);
FORCEPROP 2 LAST CDS_LIB mstr_standard
J 0
(-3700 1025);
PAINT ORANGE (-3700 1025);
DISPLAY INVISIBLE (-3700 1025);
FORCEPROP 1 LAST OFFPAGE TRUE
J 0
(-3375 900);
DISPLAY 0.936170 (-3375 900);
PAINT GREEN (-3375 900);
DISPLAY INVISIBLE (-3375 900);
FORCEPROP 1 LAST COMMENT_BODY TRUE
J 0
(-3575 925);
DISPLAY 0.936170 (-3575 925);
PAINT GREEN (-3575 925);
DISPLAY INVISIBLE (-3575 925);
FORCEPROP 2 LAST PATH I182
J 0
(-3650 1100);
PAINT ORANGE (-3650 1100);
DISPLAY INVISIBLE (-3650 1100);
FORCEADD TAP..6
R 2
(850 4550);
FORCEPROP 3 LASTPIN (800 4550) SIG_NAME M_F_DQS_DN<11>
J 0
(810 4560);
DISPLAY 0.659574 (810 4560);
PAINT MONO (810 4560);
DISPLAY INVISIBLE (810 4560);
FORCEPROP 1 LASTPIN (800 4550) BN 11
J 2
(850 4560);
DISPLAY 0.617021 (850 4560);
PAINT PINK (850 4560);
FORCEPROP 2 LAST CDS_LIB mstr_standard
J 0
(850 4550);
DISPLAY 0.787234 (850 4550);
PAINT MONO (850 4550);
DISPLAY INVISIBLE (850 4550);
FORCEPROP 1 LAST BODY_TYPE PLUMBING
J 2
(850 4500);
DISPLAY 1.234043 (850 4500);
PAINT GREEN (850 4500);
DISPLAY INVISIBLE (850 4500);
FORCEPROP 1 LAST HDL_TAP TRUE
J 2
(525 4425);
DISPLAY 1.234043 (525 4425);
PAINT GREEN (525 4425);
DISPLAY INVISIBLE (525 4425);
FORCEPROP 1 LAST PATH I19
J 2
(850 4550);
DISPLAY 0.936170 (850 4550);
PAINT GREEN (850 4550);
DISPLAY INVISIBLE (850 4550);
FORCEADD P12V_NVDIMM_DEF..1
(450 3125);
FORCEPROP 3 LASTPIN (450 3075) SIG_NAME P12V_NVDIMM_DEF\g
J 0
(460 3085);
DISPLAY 0.659574 (460 3085);
PAINT MONO (460 3085);
DISPLAY INVISIBLE (460 3085);
FORCEPROP 1 LAST VOLTAGE 12.0
J 0
(405 3082);
DISPLAY 0.340426 (405 3082);
PAINT SKYBLUE (405 3082);
DISPLAY INVISIBLE (405 3082);
FORCEPROP 2 LAST CDS_LIB mstr_symbols
J 0
(450 3125);
PAINT ORANGE (450 3125);
DISPLAY INVISIBLE (450 3125);
FORCEPROP 1 LAST BODY_TYPE PLUMBING
J 0
(405 3082);
DISPLAY 0.340426 (405 3082);
PAINT GREEN (405 3082);
DISPLAY INVISIBLE (405 3082);
FORCEPROP 1 LAST PATH I195
J 0
(500 3150);
DISPLAY 0.872340 (500 3150);
PAINT AQUA (500 3150);
DISPLAY INVISIBLE (500 3150);
FORCEPROP 1 LAST HDL_POWER P12V_NVDIMM_DEF
J 1
(450 3175);
DISPLAY 0.872340 (450 3175);
PAINT GREEN (450 3175);
DISPLAY INVISIBLE (450 3175);
FORCEADD OFFPAGE..3
(1550 5200);
FORCEPROP 2 LAST $XR0 28 
J 0
(1764 5200);
DISPLAY 0.638298 (1764 5200);
PAINT MONO (1764 5200);
FORCEPROP 2 LAST $XR1 54 
J 0
(1854 5200);
DISPLAY 0.638298 (1854 5200);
PAINT MONO (1854 5200);
FORCEPROP 2 LAST CDS_LIB mstr_standard
J 0
(1550 5200);
DISPLAY 0.787234 (1550 5200);
PAINT MONO (1550 5200);
DISPLAY INVISIBLE (1550 5200);
FORCEPROP 1 LAST OFFPAGE TRUE
J 0
(1875 5075);
DISPLAY 0.936170 (1875 5075);
PAINT GREEN (1875 5075);
DISPLAY INVISIBLE (1875 5075);
FORCEPROP 1 LAST COMMENT_BODY TRUE
J 0
(1500 5100);
DISPLAY 0.936170 (1500 5100);
PAINT GREEN (1500 5100);
DISPLAY INVISIBLE (1500 5100);
FORCEPROP 2 LAST PATH I2
J 0
(1750 5275);
DISPLAY 0.787234 (1750 5275);
PAINT MONO (1750 5275);
DISPLAY INVISIBLE (1750 5275);
FORCEADD TAP..6
R 2
(850 4450);
FORCEPROP 3 LASTPIN (800 4450) SIG_NAME M_F_DQS_DN<10>
J 0
(810 4460);
DISPLAY 0.659574 (810 4460);
PAINT MONO (810 4460);
DISPLAY INVISIBLE (810 4460);
FORCEPROP 1 LASTPIN (800 4450) BN 10
J 2
(850 4460);
DISPLAY 0.617021 (850 4460);
PAINT PINK (850 4460);
FORCEPROP 2 LAST CDS_LIB mstr_standard
J 0
(850 4450);
DISPLAY 0.787234 (850 4450);
PAINT MONO (850 4450);
DISPLAY INVISIBLE (850 4450);
FORCEPROP 1 LAST BODY_TYPE PLUMBING
J 2
(850 4400);
DISPLAY 1.234043 (850 4400);
PAINT GREEN (850 4400);
DISPLAY INVISIBLE (850 4400);
FORCEPROP 1 LAST HDL_TAP TRUE
J 2
(525 4325);
DISPLAY 1.234043 (525 4325);
PAINT GREEN (525 4325);
DISPLAY INVISIBLE (525 4325);
FORCEPROP 1 LAST PATH I20
J 2
(850 4450);
DISPLAY 0.936170 (850 4450);
PAINT GREEN (850 4450);
DISPLAY INVISIBLE (850 4450);
FORCEADD TAP..6
R 2
(850 4350);
FORCEPROP 3 LASTPIN (800 4350) SIG_NAME M_F_DQS_DN<9>
J 0
(810 4360);
DISPLAY 0.659574 (810 4360);
PAINT MONO (810 4360);
DISPLAY INVISIBLE (810 4360);
FORCEPROP 1 LASTPIN (800 4350) BN 9
J 2
(850 4360);
DISPLAY 0.617021 (850 4360);
PAINT PINK (850 4360);
FORCEPROP 2 LAST CDS_LIB mstr_standard
J 0
(850 4350);
DISPLAY 0.787234 (850 4350);
PAINT MONO (850 4350);
DISPLAY INVISIBLE (850 4350);
FORCEPROP 1 LAST BODY_TYPE PLUMBING
J 2
(850 4300);
DISPLAY 1.234043 (850 4300);
PAINT GREEN (850 4300);
DISPLAY INVISIBLE (850 4300);
FORCEPROP 1 LAST HDL_TAP TRUE
J 2
(525 4225);
DISPLAY 1.234043 (525 4225);
PAINT GREEN (525 4225);
DISPLAY INVISIBLE (525 4225);
FORCEPROP 1 LAST PATH I21
J 2
(850 4350);
DISPLAY 0.936170 (850 4350);
PAINT GREEN (850 4350);
DISPLAY INVISIBLE (850 4350);
FORCEADD TAP..6
R 2
(850 4250);
FORCEPROP 3 LASTPIN (800 4250) SIG_NAME M_F_DQS_DN<8>
J 0
(810 4260);
DISPLAY 0.659574 (810 4260);
PAINT MONO (810 4260);
DISPLAY INVISIBLE (810 4260);
FORCEPROP 1 LASTPIN (800 4250) BN 8
J 2
(850 4260);
DISPLAY 0.617021 (850 4260);
PAINT PINK (850 4260);
FORCEPROP 2 LAST CDS_LIB mstr_standard
J 0
(850 4250);
DISPLAY 0.787234 (850 4250);
PAINT MONO (850 4250);
DISPLAY INVISIBLE (850 4250);
FORCEPROP 1 LAST BODY_TYPE PLUMBING
J 2
(850 4200);
DISPLAY 1.234043 (850 4200);
PAINT GREEN (850 4200);
DISPLAY INVISIBLE (850 4200);
FORCEPROP 1 LAST HDL_TAP TRUE
J 2
(525 4125);
DISPLAY 1.234043 (525 4125);
PAINT GREEN (525 4125);
DISPLAY INVISIBLE (525 4125);
FORCEPROP 1 LAST PATH I22
J 2
(850 4250);
DISPLAY 0.936170 (850 4250);
PAINT GREEN (850 4250);
DISPLAY INVISIBLE (850 4250);
FORCEADD TAP..6
R 2
(850 4150);
FORCEPROP 3 LASTPIN (800 4150) SIG_NAME M_F_DQS_DN<7>
J 0
(810 4160);
DISPLAY 0.659574 (810 4160);
PAINT MONO (810 4160);
DISPLAY INVISIBLE (810 4160);
FORCEPROP 1 LASTPIN (800 4150) BN 7
J 2
(850 4160);
DISPLAY 0.617021 (850 4160);
PAINT PINK (850 4160);
FORCEPROP 2 LAST CDS_LIB mstr_standard
J 0
(850 4150);
DISPLAY 0.787234 (850 4150);
PAINT MONO (850 4150);
DISPLAY INVISIBLE (850 4150);
FORCEPROP 1 LAST BODY_TYPE PLUMBING
J 2
(850 4100);
DISPLAY 1.234043 (850 4100);
PAINT GREEN (850 4100);
DISPLAY INVISIBLE (850 4100);
FORCEPROP 1 LAST HDL_TAP TRUE
J 2
(525 4025);
DISPLAY 1.234043 (525 4025);
PAINT GREEN (525 4025);
DISPLAY INVISIBLE (525 4025);
FORCEPROP 1 LAST PATH I23
J 2
(850 4150);
DISPLAY 0.936170 (850 4150);
PAINT GREEN (850 4150);
DISPLAY INVISIBLE (850 4150);
FORCEADD TAP..6
R 2
(650 4400);
FORCEPROP 3 LASTPIN (600 4400) SIG_NAME M_F_DQS_DP<9>
J 0
(610 4410);
DISPLAY 0.659574 (610 4410);
PAINT MONO (610 4410);
DISPLAY INVISIBLE (610 4410);
FORCEPROP 1 LASTPIN (600 4400) BN 9
J 2
(650 4410);
DISPLAY 0.617021 (650 4410);
PAINT PINK (650 4410);
FORCEPROP 2 LAST CDS_LIB mstr_standard
J 0
(650 4400);
DISPLAY 0.787234 (650 4400);
PAINT MONO (650 4400);
DISPLAY INVISIBLE (650 4400);
FORCEPROP 1 LAST BODY_TYPE PLUMBING
J 2
(650 4350);
DISPLAY 1.234043 (650 4350);
PAINT GREEN (650 4350);
DISPLAY INVISIBLE (650 4350);
FORCEPROP 1 LAST HDL_TAP TRUE
J 2
(325 4275);
DISPLAY 1.234043 (325 4275);
PAINT GREEN (325 4275);
DISPLAY INVISIBLE (325 4275);
FORCEPROP 1 LAST PATH I24
J 2
(650 4400);
DISPLAY 0.936170 (650 4400);
PAINT GREEN (650 4400);
DISPLAY INVISIBLE (650 4400);
FORCEADD TAP..6
R 2
(650 4500);
FORCEPROP 3 LASTPIN (600 4500) SIG_NAME M_F_DQS_DP<10>
J 0
(610 4510);
DISPLAY 0.659574 (610 4510);
PAINT MONO (610 4510);
DISPLAY INVISIBLE (610 4510);
FORCEPROP 1 LASTPIN (600 4500) BN 10
J 2
(650 4510);
DISPLAY 0.617021 (650 4510);
PAINT PINK (650 4510);
FORCEPROP 2 LAST CDS_LIB mstr_standard
J 0
(650 4500);
DISPLAY 0.787234 (650 4500);
PAINT MONO (650 4500);
DISPLAY INVISIBLE (650 4500);
FORCEPROP 1 LAST BODY_TYPE PLUMBING
J 2
(650 4450);
DISPLAY 1.234043 (650 4450);
PAINT GREEN (650 4450);
DISPLAY INVISIBLE (650 4450);
FORCEPROP 1 LAST HDL_TAP TRUE
J 2
(325 4375);
DISPLAY 1.234043 (325 4375);
PAINT GREEN (325 4375);
DISPLAY INVISIBLE (325 4375);
FORCEPROP 1 LAST PATH I25
J 2
(650 4500);
DISPLAY 0.936170 (650 4500);
PAINT GREEN (650 4500);
DISPLAY INVISIBLE (650 4500);
FORCEADD TAP..6
R 2
(650 4300);
FORCEPROP 3 LASTPIN (600 4300) SIG_NAME M_F_DQS_DP<8>
J 0
(610 4310);
DISPLAY 0.659574 (610 4310);
PAINT MONO (610 4310);
DISPLAY INVISIBLE (610 4310);
FORCEPROP 1 LASTPIN (600 4300) BN 8
J 2
(650 4310);
DISPLAY 0.617021 (650 4310);
PAINT PINK (650 4310);
FORCEPROP 2 LAST CDS_LIB mstr_standard
J 0
(650 4300);
DISPLAY 0.787234 (650 4300);
PAINT MONO (650 4300);
DISPLAY INVISIBLE (650 4300);
FORCEPROP 1 LAST BODY_TYPE PLUMBING
J 2
(650 4250);
DISPLAY 1.234043 (650 4250);
PAINT GREEN (650 4250);
DISPLAY INVISIBLE (650 4250);
FORCEPROP 1 LAST HDL_TAP TRUE
J 2
(325 4175);
DISPLAY 1.234043 (325 4175);
PAINT GREEN (325 4175);
DISPLAY INVISIBLE (325 4175);
FORCEPROP 1 LAST PATH I26
J 2
(650 4300);
DISPLAY 0.936170 (650 4300);
PAINT GREEN (650 4300);
DISPLAY INVISIBLE (650 4300);
FORCEADD TAP..6
R 2
(650 4100);
FORCEPROP 3 LASTPIN (600 4100) SIG_NAME M_F_DQS_DP<6>
J 0
(610 4110);
DISPLAY 0.659574 (610 4110);
PAINT MONO (610 4110);
DISPLAY INVISIBLE (610 4110);
FORCEPROP 1 LASTPIN (600 4100) BN 6
J 2
(650 4110);
DISPLAY 0.617021 (650 4110);
PAINT PINK (650 4110);
FORCEPROP 2 LAST CDS_LIB mstr_standard
J 0
(650 4100);
DISPLAY 0.787234 (650 4100);
PAINT MONO (650 4100);
DISPLAY INVISIBLE (650 4100);
FORCEPROP 1 LAST BODY_TYPE PLUMBING
J 2
(650 4050);
DISPLAY 1.234043 (650 4050);
PAINT GREEN (650 4050);
DISPLAY INVISIBLE (650 4050);
FORCEPROP 1 LAST HDL_TAP TRUE
J 2
(325 3975);
DISPLAY 1.234043 (325 3975);
PAINT GREEN (325 3975);
DISPLAY INVISIBLE (325 3975);
FORCEPROP 1 LAST PATH I27
J 2
(650 4100);
DISPLAY 0.936170 (650 4100);
PAINT GREEN (650 4100);
DISPLAY INVISIBLE (650 4100);
FORCEADD TAP..6
R 2
(650 4200);
FORCEPROP 3 LASTPIN (600 4200) SIG_NAME M_F_DQS_DP<7>
J 0
(610 4210);
DISPLAY 0.659574 (610 4210);
PAINT MONO (610 4210);
DISPLAY INVISIBLE (610 4210);
FORCEPROP 1 LASTPIN (600 4200) BN 7
J 2
(650 4210);
DISPLAY 0.617021 (650 4210);
PAINT PINK (650 4210);
FORCEPROP 2 LAST CDS_LIB mstr_standard
J 0
(650 4200);
DISPLAY 0.787234 (650 4200);
PAINT MONO (650 4200);
DISPLAY INVISIBLE (650 4200);
FORCEPROP 1 LAST BODY_TYPE PLUMBING
J 2
(650 4150);
DISPLAY 1.234043 (650 4150);
PAINT GREEN (650 4150);
DISPLAY INVISIBLE (650 4150);
FORCEPROP 1 LAST HDL_TAP TRUE
J 2
(325 4075);
DISPLAY 1.234043 (325 4075);
PAINT GREEN (325 4075);
DISPLAY INVISIBLE (325 4075);
FORCEPROP 1 LAST PATH I28
J 2
(650 4200);
DISPLAY 0.936170 (650 4200);
PAINT GREEN (650 4200);
DISPLAY INVISIBLE (650 4200);
FORCEADD TAP..6
R 2
(850 4050);
FORCEPROP 3 LASTPIN (800 4050) SIG_NAME M_F_DQS_DN<6>
J 0
(810 4060);
DISPLAY 0.659574 (810 4060);
PAINT MONO (810 4060);
DISPLAY INVISIBLE (810 4060);
FORCEPROP 1 LASTPIN (800 4050) BN 6
J 2
(850 4060);
DISPLAY 0.617021 (850 4060);
PAINT PINK (850 4060);
FORCEPROP 2 LAST CDS_LIB mstr_standard
J 0
(850 4050);
DISPLAY 0.787234 (850 4050);
PAINT MONO (850 4050);
DISPLAY INVISIBLE (850 4050);
FORCEPROP 1 LAST BODY_TYPE PLUMBING
J 2
(850 4000);
DISPLAY 1.234043 (850 4000);
PAINT GREEN (850 4000);
DISPLAY INVISIBLE (850 4000);
FORCEPROP 1 LAST HDL_TAP TRUE
J 2
(525 3925);
DISPLAY 1.234043 (525 3925);
PAINT GREEN (525 3925);
DISPLAY INVISIBLE (525 3925);
FORCEPROP 1 LAST PATH I29
J 2
(850 4050);
DISPLAY 0.936170 (850 4050);
PAINT GREEN (850 4050);
DISPLAY INVISIBLE (850 4050);
FORCEADD TAP..6
R 2
(850 5150);
FORCEPROP 3 LASTPIN (800 5150) SIG_NAME M_F_DQS_DN<17>
J 0
(810 5160);
DISPLAY 0.659574 (810 5160);
PAINT MONO (810 5160);
DISPLAY INVISIBLE (810 5160);
FORCEPROP 1 LASTPIN (800 5150) BN 17
J 2
(850 5160);
DISPLAY 0.617021 (850 5160);
PAINT PINK (850 5160);
FORCEPROP 2 LAST CDS_LIB mstr_standard
J 2
(850 5150);
DISPLAY 0.787234 (850 5150);
PAINT MONO (850 5150);
DISPLAY INVISIBLE (850 5150);
FORCEPROP 1 LAST BODY_TYPE PLUMBING
J 2
(850 5100);
DISPLAY 1.234043 (850 5100);
PAINT GREEN (850 5100);
DISPLAY INVISIBLE (850 5100);
FORCEPROP 1 LAST HDL_TAP TRUE
J 2
(525 5025);
DISPLAY 1.234043 (525 5025);
PAINT GREEN (525 5025);
DISPLAY INVISIBLE (525 5025);
FORCEPROP 1 LAST PATH I3
J 2
(850 5150);
DISPLAY 0.936170 (850 5150);
PAINT GREEN (850 5150);
DISPLAY INVISIBLE (850 5150);
FORCEADD TAP..6
R 2
(850 3950);
FORCEPROP 3 LASTPIN (800 3950) SIG_NAME M_F_DQS_DN<5>
J 0
(810 3960);
DISPLAY 0.659574 (810 3960);
PAINT MONO (810 3960);
DISPLAY INVISIBLE (810 3960);
FORCEPROP 1 LASTPIN (800 3950) BN 5
J 2
(850 3960);
DISPLAY 0.617021 (850 3960);
PAINT PINK (850 3960);
FORCEPROP 2 LAST CDS_LIB mstr_standard
J 0
(850 3950);
DISPLAY 0.787234 (850 3950);
PAINT MONO (850 3950);
DISPLAY INVISIBLE (850 3950);
FORCEPROP 1 LAST BODY_TYPE PLUMBING
J 2
(850 3900);
DISPLAY 1.234043 (850 3900);
PAINT GREEN (850 3900);
DISPLAY INVISIBLE (850 3900);
FORCEPROP 1 LAST HDL_TAP TRUE
J 2
(525 3825);
DISPLAY 1.234043 (525 3825);
PAINT GREEN (525 3825);
DISPLAY INVISIBLE (525 3825);
FORCEPROP 1 LAST PATH I30
J 2
(850 3950);
DISPLAY 0.936170 (850 3950);
PAINT GREEN (850 3950);
DISPLAY INVISIBLE (850 3950);
FORCEADD TAP..6
R 2
(850 3850);
FORCEPROP 3 LASTPIN (800 3850) SIG_NAME M_F_DQS_DN<4>
J 0
(810 3860);
DISPLAY 0.659574 (810 3860);
PAINT MONO (810 3860);
DISPLAY INVISIBLE (810 3860);
FORCEPROP 1 LASTPIN (800 3850) BN 4
J 2
(850 3860);
DISPLAY 0.617021 (850 3860);
PAINT PINK (850 3860);
FORCEPROP 2 LAST CDS_LIB mstr_standard
J 0
(850 3850);
DISPLAY 0.787234 (850 3850);
PAINT MONO (850 3850);
DISPLAY INVISIBLE (850 3850);
FORCEPROP 1 LAST BODY_TYPE PLUMBING
J 2
(850 3800);
DISPLAY 1.234043 (850 3800);
PAINT GREEN (850 3800);
DISPLAY INVISIBLE (850 3800);
FORCEPROP 1 LAST HDL_TAP TRUE
J 2
(525 3725);
DISPLAY 1.234043 (525 3725);
PAINT GREEN (525 3725);
DISPLAY INVISIBLE (525 3725);
FORCEPROP 1 LAST PATH I31
J 2
(850 3850);
DISPLAY 0.936170 (850 3850);
PAINT GREEN (850 3850);
DISPLAY INVISIBLE (850 3850);
FORCEADD TAP..6
R 2
(850 3750);
FORCEPROP 3 LASTPIN (800 3750) SIG_NAME M_F_DQS_DN<3>
J 0
(810 3760);
DISPLAY 0.659574 (810 3760);
PAINT MONO (810 3760);
DISPLAY INVISIBLE (810 3760);
FORCEPROP 1 LASTPIN (800 3750) BN 3
J 2
(850 3760);
DISPLAY 0.617021 (850 3760);
PAINT PINK (850 3760);
FORCEPROP 2 LAST CDS_LIB mstr_standard
J 0
(850 3750);
DISPLAY 0.787234 (850 3750);
PAINT MONO (850 3750);
DISPLAY INVISIBLE (850 3750);
FORCEPROP 1 LAST BODY_TYPE PLUMBING
J 2
(850 3700);
DISPLAY 1.234043 (850 3700);
PAINT GREEN (850 3700);
DISPLAY INVISIBLE (850 3700);
FORCEPROP 1 LAST HDL_TAP TRUE
J 2
(525 3625);
DISPLAY 1.234043 (525 3625);
PAINT GREEN (525 3625);
DISPLAY INVISIBLE (525 3625);
FORCEPROP 1 LAST PATH I32
J 2
(850 3750);
DISPLAY 0.936170 (850 3750);
PAINT GREEN (850 3750);
DISPLAY INVISIBLE (850 3750);
FORCEADD TAP..6
R 2
(850 3650);
FORCEPROP 3 LASTPIN (800 3650) SIG_NAME M_F_DQS_DN<2>
J 0
(810 3660);
DISPLAY 0.659574 (810 3660);
PAINT MONO (810 3660);
DISPLAY INVISIBLE (810 3660);
FORCEPROP 1 LASTPIN (800 3650) BN 2
J 2
(850 3660);
DISPLAY 0.617021 (850 3660);
PAINT PINK (850 3660);
FORCEPROP 2 LAST CDS_LIB mstr_standard
J 0
(850 3650);
DISPLAY 0.787234 (850 3650);
PAINT MONO (850 3650);
DISPLAY INVISIBLE (850 3650);
FORCEPROP 1 LAST BODY_TYPE PLUMBING
J 2
(850 3600);
DISPLAY 1.234043 (850 3600);
PAINT GREEN (850 3600);
DISPLAY INVISIBLE (850 3600);
FORCEPROP 1 LAST HDL_TAP TRUE
J 2
(525 3525);
DISPLAY 1.234043 (525 3525);
PAINT GREEN (525 3525);
DISPLAY INVISIBLE (525 3525);
FORCEPROP 1 LAST PATH I33
J 2
(850 3650);
DISPLAY 0.936170 (850 3650);
PAINT GREEN (850 3650);
DISPLAY INVISIBLE (850 3650);
FORCEADD TAP..6
R 2
(650 3900);
FORCEPROP 3 LASTPIN (600 3900) SIG_NAME M_F_DQS_DP<4>
J 0
(610 3910);
DISPLAY 0.659574 (610 3910);
PAINT MONO (610 3910);
DISPLAY INVISIBLE (610 3910);
FORCEPROP 1 LASTPIN (600 3900) BN 4
J 2
(650 3910);
DISPLAY 0.617021 (650 3910);
PAINT PINK (650 3910);
FORCEPROP 2 LAST CDS_LIB mstr_standard
J 0
(650 3900);
DISPLAY 0.787234 (650 3900);
PAINT MONO (650 3900);
DISPLAY INVISIBLE (650 3900);
FORCEPROP 1 LAST BODY_TYPE PLUMBING
J 2
(650 3850);
DISPLAY 1.234043 (650 3850);
PAINT GREEN (650 3850);
DISPLAY INVISIBLE (650 3850);
FORCEPROP 1 LAST HDL_TAP TRUE
J 2
(325 3775);
DISPLAY 1.234043 (325 3775);
PAINT GREEN (325 3775);
DISPLAY INVISIBLE (325 3775);
FORCEPROP 1 LAST PATH I34
J 2
(650 3900);
DISPLAY 0.936170 (650 3900);
PAINT GREEN (650 3900);
DISPLAY INVISIBLE (650 3900);
FORCEADD TAP..6
R 2
(650 4000);
FORCEPROP 3 LASTPIN (600 4000) SIG_NAME M_F_DQS_DP<5>
J 0
(610 4010);
DISPLAY 0.659574 (610 4010);
PAINT MONO (610 4010);
DISPLAY INVISIBLE (610 4010);
FORCEPROP 1 LASTPIN (600 4000) BN 5
J 2
(650 4010);
DISPLAY 0.617021 (650 4010);
PAINT PINK (650 4010);
FORCEPROP 2 LAST CDS_LIB mstr_standard
J 0
(650 4000);
DISPLAY 0.787234 (650 4000);
PAINT MONO (650 4000);
DISPLAY INVISIBLE (650 4000);
FORCEPROP 1 LAST BODY_TYPE PLUMBING
J 2
(650 3950);
DISPLAY 1.234043 (650 3950);
PAINT GREEN (650 3950);
DISPLAY INVISIBLE (650 3950);
FORCEPROP 1 LAST HDL_TAP TRUE
J 2
(325 3875);
DISPLAY 1.234043 (325 3875);
PAINT GREEN (325 3875);
DISPLAY INVISIBLE (325 3875);
FORCEPROP 1 LAST PATH I35
J 2
(650 4000);
DISPLAY 0.936170 (650 4000);
PAINT GREEN (650 4000);
DISPLAY INVISIBLE (650 4000);
FORCEADD TAP..6
R 2
(650 3800);
FORCEPROP 3 LASTPIN (600 3800) SIG_NAME M_F_DQS_DP<3>
J 0
(610 3810);
DISPLAY 0.659574 (610 3810);
PAINT MONO (610 3810);
DISPLAY INVISIBLE (610 3810);
FORCEPROP 1 LASTPIN (600 3800) BN 3
J 2
(650 3810);
DISPLAY 0.617021 (650 3810);
PAINT PINK (650 3810);
FORCEPROP 2 LAST CDS_LIB mstr_standard
J 0
(650 3800);
DISPLAY 0.787234 (650 3800);
PAINT MONO (650 3800);
DISPLAY INVISIBLE (650 3800);
FORCEPROP 1 LAST BODY_TYPE PLUMBING
J 2
(650 3750);
DISPLAY 1.234043 (650 3750);
PAINT GREEN (650 3750);
DISPLAY INVISIBLE (650 3750);
FORCEPROP 1 LAST HDL_TAP TRUE
J 2
(325 3675);
DISPLAY 1.234043 (325 3675);
PAINT GREEN (325 3675);
DISPLAY INVISIBLE (325 3675);
FORCEPROP 1 LAST PATH I36
J 2
(650 3800);
DISPLAY 0.936170 (650 3800);
PAINT GREEN (650 3800);
DISPLAY INVISIBLE (650 3800);
FORCEADD TAP..6
R 2
(650 3700);
FORCEPROP 3 LASTPIN (600 3700) SIG_NAME M_F_DQS_DP<2>
J 0
(610 3710);
DISPLAY 0.659574 (610 3710);
PAINT MONO (610 3710);
DISPLAY INVISIBLE (610 3710);
FORCEPROP 1 LASTPIN (600 3700) BN 2
J 2
(650 3710);
DISPLAY 0.617021 (650 3710);
PAINT PINK (650 3710);
FORCEPROP 2 LAST CDS_LIB mstr_standard
J 0
(650 3700);
DISPLAY 0.787234 (650 3700);
PAINT MONO (650 3700);
DISPLAY INVISIBLE (650 3700);
FORCEPROP 1 LAST BODY_TYPE PLUMBING
J 2
(650 3650);
DISPLAY 1.234043 (650 3650);
PAINT GREEN (650 3650);
DISPLAY INVISIBLE (650 3650);
FORCEPROP 1 LAST HDL_TAP TRUE
J 2
(325 3575);
DISPLAY 1.234043 (325 3575);
PAINT GREEN (325 3575);
DISPLAY INVISIBLE (325 3575);
FORCEPROP 1 LAST PATH I37
J 2
(650 3700);
DISPLAY 0.936170 (650 3700);
PAINT GREEN (650 3700);
DISPLAY INVISIBLE (650 3700);
FORCEADD TAP..6
R 2
(650 3600);
FORCEPROP 3 LASTPIN (600 3600) SIG_NAME M_F_DQS_DP<1>
J 0
(610 3610);
DISPLAY 0.659574 (610 3610);
PAINT MONO (610 3610);
DISPLAY INVISIBLE (610 3610);
FORCEPROP 1 LASTPIN (600 3600) BN 1
J 2
(650 3610);
DISPLAY 0.617021 (650 3610);
PAINT PINK (650 3610);
FORCEPROP 2 LAST CDS_LIB mstr_standard
J 0
(650 3600);
DISPLAY 0.787234 (650 3600);
PAINT MONO (650 3600);
DISPLAY INVISIBLE (650 3600);
FORCEPROP 1 LAST BODY_TYPE PLUMBING
J 2
(650 3550);
DISPLAY 1.234043 (650 3550);
PAINT GREEN (650 3550);
DISPLAY INVISIBLE (650 3550);
FORCEPROP 1 LAST HDL_TAP TRUE
J 2
(325 3475);
DISPLAY 1.234043 (325 3475);
PAINT GREEN (325 3475);
DISPLAY INVISIBLE (325 3475);
FORCEPROP 1 LAST PATH I38
J 2
(650 3600);
DISPLAY 0.936170 (650 3600);
PAINT GREEN (650 3600);
DISPLAY INVISIBLE (650 3600);
FORCEADD TAP..6
R 2
(850 3450);
FORCEPROP 3 LASTPIN (800 3450) SIG_NAME M_F_DQS_DN<0>
J 0
(810 3460);
DISPLAY 0.659574 (810 3460);
PAINT MONO (810 3460);
DISPLAY INVISIBLE (810 3460);
FORCEPROP 1 LASTPIN (800 3450) BN 0
J 2
(850 3460);
DISPLAY 0.617021 (850 3460);
PAINT PINK (850 3460);
FORCEPROP 2 LAST CDS_LIB mstr_standard
J 0
(850 3450);
DISPLAY 0.787234 (850 3450);
PAINT MONO (850 3450);
DISPLAY INVISIBLE (850 3450);
FORCEPROP 1 LAST BODY_TYPE PLUMBING
J 2
(850 3400);
DISPLAY 1.234043 (850 3400);
PAINT GREEN (850 3400);
DISPLAY INVISIBLE (850 3400);
FORCEPROP 1 LAST HDL_TAP TRUE
J 2
(525 3325);
DISPLAY 1.234043 (525 3325);
PAINT GREEN (525 3325);
DISPLAY INVISIBLE (525 3325);
FORCEPROP 1 LAST PATH I39
J 2
(850 3450);
DISPLAY 0.936170 (850 3450);
PAINT GREEN (850 3450);
DISPLAY INVISIBLE (850 3450);
FORCEADD TAP..6
R 2
(650 5200);
FORCEPROP 3 LASTPIN (600 5200) SIG_NAME M_F_DQS_DP<17>
J 0
(610 5210);
DISPLAY 0.659574 (610 5210);
PAINT MONO (610 5210);
DISPLAY INVISIBLE (610 5210);
FORCEPROP 1 LASTPIN (600 5200) BN 17
J 2
(650 5210);
DISPLAY 0.617021 (650 5210);
PAINT PINK (650 5210);
FORCEPROP 2 LAST CDS_LIB mstr_standard
J 2
(650 5200);
DISPLAY 0.787234 (650 5200);
PAINT MONO (650 5200);
DISPLAY INVISIBLE (650 5200);
FORCEPROP 1 LAST BODY_TYPE PLUMBING
J 2
(650 5150);
DISPLAY 1.234043 (650 5150);
PAINT GREEN (650 5150);
DISPLAY INVISIBLE (650 5150);
FORCEPROP 1 LAST HDL_TAP TRUE
J 2
(325 5075);
DISPLAY 1.234043 (325 5075);
PAINT GREEN (325 5075);
DISPLAY INVISIBLE (325 5075);
FORCEPROP 1 LAST PATH I4
J 2
(650 5200);
DISPLAY 0.936170 (650 5200);
PAINT GREEN (650 5200);
DISPLAY INVISIBLE (650 5200);
FORCEADD TAP..6
R 2
(850 3550);
FORCEPROP 3 LASTPIN (800 3550) SIG_NAME M_F_DQS_DN<1>
J 0
(810 3560);
DISPLAY 0.659574 (810 3560);
PAINT MONO (810 3560);
DISPLAY INVISIBLE (810 3560);
FORCEPROP 1 LASTPIN (800 3550) BN 1
J 2
(850 3560);
DISPLAY 0.617021 (850 3560);
PAINT PINK (850 3560);
FORCEPROP 2 LAST CDS_LIB mstr_standard
J 0
(850 3550);
DISPLAY 0.787234 (850 3550);
PAINT MONO (850 3550);
DISPLAY INVISIBLE (850 3550);
FORCEPROP 1 LAST BODY_TYPE PLUMBING
J 2
(850 3500);
DISPLAY 1.234043 (850 3500);
PAINT GREEN (850 3500);
DISPLAY INVISIBLE (850 3500);
FORCEPROP 1 LAST HDL_TAP TRUE
J 2
(525 3425);
DISPLAY 1.234043 (525 3425);
PAINT GREEN (525 3425);
DISPLAY INVISIBLE (525 3425);
FORCEPROP 1 LAST PATH I40
J 2
(850 3550);
DISPLAY 0.936170 (850 3550);
PAINT GREEN (850 3550);
DISPLAY INVISIBLE (850 3550);
FORCEADD TAP..6
R 2
(650 3500);
FORCEPROP 3 LASTPIN (600 3500) SIG_NAME M_F_DQS_DP<0>
J 0
(610 3510);
DISPLAY 0.659574 (610 3510);
PAINT MONO (610 3510);
DISPLAY INVISIBLE (610 3510);
FORCEPROP 1 LASTPIN (600 3500) BN 0
J 2
(650 3510);
DISPLAY 0.617021 (650 3510);
PAINT PINK (650 3510);
FORCEPROP 2 LAST CDS_LIB mstr_standard
J 0
(650 3500);
DISPLAY 0.787234 (650 3500);
PAINT MONO (650 3500);
DISPLAY INVISIBLE (650 3500);
FORCEPROP 1 LAST BODY_TYPE PLUMBING
J 2
(650 3450);
DISPLAY 1.234043 (650 3450);
PAINT GREEN (650 3450);
DISPLAY INVISIBLE (650 3450);
FORCEPROP 1 LAST HDL_TAP TRUE
J 2
(325 3375);
DISPLAY 1.234043 (325 3375);
PAINT GREEN (325 3375);
DISPLAY INVISIBLE (325 3375);
FORCEPROP 1 LAST PATH I41
J 2
(650 3500);
DISPLAY 0.936170 (650 3500);
PAINT GREEN (650 3500);
DISPLAY INVISIBLE (650 3500);
FORCEADD SCONN288_H44441004..3
(1750 2400);
FORCEPROP 1 LAST LOCATION J4A1
J 0
(1300 3800);
DISPLAY 0.617021 (1300 3800);
PAINT AQUA (1300 3800);
FORCEPROP 1 LAST PART_NUMBER H44441-004
J 0
(1300 1050);
DISPLAY 0.617021 (1300 1050);
PAINT BLUE (1300 1050);
FORCEPROP 1 LAST MATERIAL SCONN
J 0
(1300 3750);
DISPLAY 0.617021 (1300 3750);
PAINT SKYBLUE (1300 3750);
FORCEPROP 2 LASTPIN (1250 3550) $PN 2
J 2
(1240 3560);
DISPLAY 0.617021 (1240 3560);
PAINT ORANGE (1240 3560);
FORCEPROP 2 LASTPIN (1250 3500) $PN 4
J 2
(1240 3510);
DISPLAY 0.617021 (1240 3510);
PAINT ORANGE (1240 3510);
FORCEPROP 2 LASTPIN (1250 3450) $PN 6
J 2
(1240 3460);
DISPLAY 0.617021 (1240 3460);
PAINT ORANGE (1240 3460);
FORCEPROP 2 LASTPIN (1250 3400) $PN 9
J 2
(1240 3410);
DISPLAY 0.617021 (1240 3410);
PAINT ORANGE (1240 3410);
FORCEPROP 2 LASTPIN (1250 3350) $PN 11
J 2
(1240 3360);
DISPLAY 0.617021 (1240 3360);
PAINT ORANGE (1240 3360);
FORCEPROP 2 LASTPIN (1250 3300) $PN 13
J 2
(1240 3310);
DISPLAY 0.617021 (1240 3310);
PAINT ORANGE (1240 3310);
FORCEPROP 2 LASTPIN (1250 3250) $PN 15
J 2
(1240 3260);
DISPLAY 0.617021 (1240 3260);
PAINT ORANGE (1240 3260);
FORCEPROP 2 LASTPIN (1250 3200) $PN 17
J 2
(1240 3210);
DISPLAY 0.617021 (1240 3210);
PAINT ORANGE (1240 3210);
FORCEPROP 2 LASTPIN (1250 3150) $PN 20
J 2
(1240 3160);
DISPLAY 0.617021 (1240 3160);
PAINT ORANGE (1240 3160);
FORCEPROP 2 LASTPIN (1250 3100) $PN 22
J 2
(1240 3110);
DISPLAY 0.617021 (1240 3110);
PAINT ORANGE (1240 3110);
FORCEPROP 2 LASTPIN (1250 3050) $PN 24
J 2
(1240 3060);
DISPLAY 0.617021 (1240 3060);
PAINT ORANGE (1240 3060);
FORCEPROP 2 LASTPIN (1250 3000) $PN 26
J 2
(1240 3010);
DISPLAY 0.617021 (1240 3010);
PAINT ORANGE (1240 3010);
FORCEPROP 2 LASTPIN (1250 2950) $PN 28
J 2
(1240 2960);
DISPLAY 0.617021 (1240 2960);
PAINT ORANGE (1240 2960);
FORCEPROP 2 LASTPIN (1250 2900) $PN 31
J 2
(1240 2910);
DISPLAY 0.617021 (1240 2910);
PAINT ORANGE (1240 2910);
FORCEPROP 2 LASTPIN (1250 2850) $PN 33
J 2
(1240 2860);
DISPLAY 0.617021 (1240 2860);
PAINT ORANGE (1240 2860);
FORCEPROP 2 LASTPIN (1250 2800) $PN 35
J 2
(1240 2810);
DISPLAY 0.617021 (1240 2810);
PAINT ORANGE (1240 2810);
FORCEPROP 2 LASTPIN (1250 2750) $PN 37
J 2
(1240 2760);
DISPLAY 0.617021 (1240 2760);
PAINT ORANGE (1240 2760);
FORCEPROP 2 LASTPIN (1250 2700) $PN 39
J 2
(1240 2710);
DISPLAY 0.617021 (1240 2710);
PAINT ORANGE (1240 2710);
FORCEPROP 2 LASTPIN (1250 2650) $PN 42
J 2
(1240 2660);
DISPLAY 0.617021 (1240 2660);
PAINT ORANGE (1240 2660);
FORCEPROP 2 LASTPIN (1250 2600) $PN 44
J 2
(1240 2610);
DISPLAY 0.617021 (1240 2610);
PAINT ORANGE (1240 2610);
FORCEPROP 2 LASTPIN (1250 2550) $PN 46
J 2
(1240 2560);
DISPLAY 0.617021 (1240 2560);
PAINT ORANGE (1240 2560);
FORCEPROP 2 LASTPIN (1250 2500) $PN 48
J 2
(1240 2510);
DISPLAY 0.617021 (1240 2510);
PAINT ORANGE (1240 2510);
FORCEPROP 2 LASTPIN (1250 2450) $PN 50
J 2
(1240 2460);
DISPLAY 0.617021 (1240 2460);
PAINT ORANGE (1240 2460);
FORCEPROP 2 LASTPIN (1250 2400) $PN 53
J 2
(1240 2410);
DISPLAY 0.617021 (1240 2410);
PAINT ORANGE (1240 2410);
FORCEPROP 2 LASTPIN (1250 2350) $PN 55
J 2
(1240 2360);
DISPLAY 0.617021 (1240 2360);
PAINT ORANGE (1240 2360);
FORCEPROP 2 LASTPIN (1250 2300) $PN 57
J 2
(1240 2310);
DISPLAY 0.617021 (1240 2310);
PAINT ORANGE (1240 2310);
FORCEPROP 2 LASTPIN (1250 2250) $PN 94
J 2
(1240 2260);
DISPLAY 0.617021 (1240 2260);
PAINT ORANGE (1240 2260);
FORCEPROP 2 LASTPIN (1250 2200) $PN 96
J 2
(1240 2210);
DISPLAY 0.617021 (1240 2210);
PAINT ORANGE (1240 2210);
FORCEPROP 2 LASTPIN (1250 2150) $PN 98
J 2
(1240 2160);
DISPLAY 0.617021 (1240 2160);
PAINT ORANGE (1240 2160);
FORCEPROP 2 LASTPIN (1250 2100) $PN 101
J 2
(1240 2110);
DISPLAY 0.617021 (1240 2110);
PAINT ORANGE (1240 2110);
FORCEPROP 2 LASTPIN (1250 2050) $PN 103
J 2
(1240 2060);
DISPLAY 0.617021 (1240 2060);
PAINT ORANGE (1240 2060);
FORCEPROP 2 LASTPIN (1250 2000) $PN 105
J 2
(1240 2010);
DISPLAY 0.617021 (1240 2010);
PAINT ORANGE (1240 2010);
FORCEPROP 2 LASTPIN (1250 1950) $PN 107
J 2
(1240 1960);
DISPLAY 0.617021 (1240 1960);
PAINT ORANGE (1240 1960);
FORCEPROP 2 LASTPIN (1250 1900) $PN 109
J 2
(1240 1910);
DISPLAY 0.617021 (1240 1910);
PAINT ORANGE (1240 1910);
FORCEPROP 2 LASTPIN (1250 1850) $PN 112
J 2
(1240 1860);
DISPLAY 0.617021 (1240 1860);
PAINT ORANGE (1240 1860);
FORCEPROP 2 LASTPIN (1250 1800) $PN 114
J 2
(1240 1810);
DISPLAY 0.617021 (1240 1810);
PAINT ORANGE (1240 1810);
FORCEPROP 2 LASTPIN (1250 1750) $PN 116
J 2
(1240 1760);
DISPLAY 0.617021 (1240 1760);
PAINT ORANGE (1240 1760);
FORCEPROP 2 LASTPIN (1250 1700) $PN 118
J 2
(1240 1710);
DISPLAY 0.617021 (1240 1710);
PAINT ORANGE (1240 1710);
FORCEPROP 2 LASTPIN (1250 1650) $PN 120
J 2
(1240 1660);
DISPLAY 0.617021 (1240 1660);
PAINT ORANGE (1240 1660);
FORCEPROP 2 LASTPIN (1250 1600) $PN 123
J 2
(1240 1610);
DISPLAY 0.617021 (1240 1610);
PAINT ORANGE (1240 1610);
FORCEPROP 2 LASTPIN (1250 1550) $PN 125
J 2
(1240 1560);
DISPLAY 0.617021 (1240 1560);
PAINT ORANGE (1240 1560);
FORCEPROP 2 LASTPIN (1250 1500) $PN 127
J 2
(1240 1510);
DISPLAY 0.617021 (1240 1510);
PAINT ORANGE (1240 1510);
FORCEPROP 2 LASTPIN (1250 1450) $PN 129
J 2
(1240 1460);
DISPLAY 0.617021 (1240 1460);
PAINT ORANGE (1240 1460);
FORCEPROP 2 LASTPIN (1250 1400) $PN 131
J 2
(1240 1410);
DISPLAY 0.617021 (1240 1410);
PAINT ORANGE (1240 1410);
FORCEPROP 2 LASTPIN (1250 1350) $PN 134
J 2
(1240 1360);
DISPLAY 0.617021 (1240 1360);
PAINT ORANGE (1240 1360);
FORCEPROP 2 LASTPIN (1250 1300) $PN 136
J 2
(1240 1310);
DISPLAY 0.617021 (1240 1310);
PAINT ORANGE (1240 1310);
FORCEPROP 2 LASTPIN (1250 1250) $PN 138
J 2
(1240 1260);
DISPLAY 0.617021 (1240 1260);
PAINT ORANGE (1240 1260);
FORCEPROP 2 LASTPIN (2250 3550) $PN 147
J 0
(2260 3560);
DISPLAY 0.617021 (2260 3560);
PAINT ORANGE (2260 3560);
FORCEPROP 2 LASTPIN (2250 3500) $PN 149
J 0
(2260 3510);
DISPLAY 0.617021 (2260 3510);
PAINT ORANGE (2260 3510);
FORCEPROP 2 LASTPIN (2250 3450) $PN 151
J 0
(2260 3460);
DISPLAY 0.617021 (2260 3460);
PAINT ORANGE (2260 3460);
FORCEPROP 2 LASTPIN (2250 3400) $PN 154
J 0
(2260 3410);
DISPLAY 0.617021 (2260 3410);
PAINT ORANGE (2260 3410);
FORCEPROP 2 LASTPIN (2250 3350) $PN 156
J 0
(2260 3360);
DISPLAY 0.617021 (2260 3360);
PAINT ORANGE (2260 3360);
FORCEPROP 2 LASTPIN (2250 3300) $PN 158
J 0
(2260 3310);
DISPLAY 0.617021 (2260 3310);
PAINT ORANGE (2260 3310);
FORCEPROP 2 LASTPIN (2250 3250) $PN 160
J 0
(2260 3260);
DISPLAY 0.617021 (2260 3260);
PAINT ORANGE (2260 3260);
FORCEPROP 2 LASTPIN (2250 3200) $PN 162
J 0
(2260 3210);
DISPLAY 0.617021 (2260 3210);
PAINT ORANGE (2260 3210);
FORCEPROP 2 LASTPIN (2250 3150) $PN 165
J 0
(2260 3160);
DISPLAY 0.617021 (2260 3160);
PAINT ORANGE (2260 3160);
FORCEPROP 2 LASTPIN (2250 3100) $PN 167
J 0
(2260 3110);
DISPLAY 0.617021 (2260 3110);
PAINT ORANGE (2260 3110);
FORCEPROP 2 LASTPIN (2250 3050) $PN 169
J 0
(2260 3060);
DISPLAY 0.617021 (2260 3060);
PAINT ORANGE (2260 3060);
FORCEPROP 2 LASTPIN (2250 3000) $PN 171
J 0
(2260 3010);
DISPLAY 0.617021 (2260 3010);
PAINT ORANGE (2260 3010);
FORCEPROP 2 LASTPIN (2250 2950) $PN 173
J 0
(2260 2960);
DISPLAY 0.617021 (2260 2960);
PAINT ORANGE (2260 2960);
FORCEPROP 2 LASTPIN (2250 2900) $PN 176
J 0
(2260 2910);
DISPLAY 0.617021 (2260 2910);
PAINT ORANGE (2260 2910);
FORCEPROP 2 LASTPIN (2250 2850) $PN 178
J 0
(2260 2860);
DISPLAY 0.617021 (2260 2860);
PAINT ORANGE (2260 2860);
FORCEPROP 2 LASTPIN (2250 2800) $PN 180
J 0
(2260 2810);
DISPLAY 0.617021 (2260 2810);
PAINT ORANGE (2260 2810);
FORCEPROP 2 LASTPIN (2250 2750) $PN 182
J 0
(2260 2760);
DISPLAY 0.617021 (2260 2760);
PAINT ORANGE (2260 2760);
FORCEPROP 2 LASTPIN (2250 2700) $PN 184
J 0
(2260 2710);
DISPLAY 0.617021 (2260 2710);
PAINT ORANGE (2260 2710);
FORCEPROP 2 LASTPIN (2250 2650) $PN 187
J 0
(2260 2660);
DISPLAY 0.617021 (2260 2660);
PAINT ORANGE (2260 2660);
FORCEPROP 2 LASTPIN (2250 2600) $PN 189
J 0
(2260 2610);
DISPLAY 0.617021 (2260 2610);
PAINT ORANGE (2260 2610);
FORCEPROP 2 LASTPIN (2250 2550) $PN 191
J 0
(2260 2560);
DISPLAY 0.617021 (2260 2560);
PAINT ORANGE (2260 2560);
FORCEPROP 2 LASTPIN (2250 2500) $PN 193
J 0
(2260 2510);
DISPLAY 0.617021 (2260 2510);
PAINT ORANGE (2260 2510);
FORCEPROP 2 LASTPIN (2250 2450) $PN 195
J 0
(2260 2460);
DISPLAY 0.617021 (2260 2460);
PAINT ORANGE (2260 2460);
FORCEPROP 2 LASTPIN (2250 2400) $PN 198
J 0
(2260 2410);
DISPLAY 0.617021 (2260 2410);
PAINT ORANGE (2260 2410);
FORCEPROP 2 LASTPIN (2250 2350) $PN 200
J 0
(2260 2360);
DISPLAY 0.617021 (2260 2360);
PAINT ORANGE (2260 2360);
FORCEPROP 2 LASTPIN (2250 2300) $PN 202
J 0
(2260 2310);
DISPLAY 0.617021 (2260 2310);
PAINT ORANGE (2260 2310);
FORCEPROP 2 LASTPIN (2250 2250) $PN 239
J 0
(2260 2260);
DISPLAY 0.617021 (2260 2260);
PAINT ORANGE (2260 2260);
FORCEPROP 2 LASTPIN (2250 2200) $PN 241
J 0
(2260 2210);
DISPLAY 0.617021 (2260 2210);
PAINT ORANGE (2260 2210);
FORCEPROP 2 LASTPIN (2250 2150) $PN 243
J 0
(2260 2160);
DISPLAY 0.617021 (2260 2160);
PAINT ORANGE (2260 2160);
FORCEPROP 2 LASTPIN (2250 2100) $PN 246
J 0
(2260 2110);
DISPLAY 0.617021 (2260 2110);
PAINT ORANGE (2260 2110);
FORCEPROP 2 LASTPIN (2250 2050) $PN 248
J 0
(2260 2060);
DISPLAY 0.617021 (2260 2060);
PAINT ORANGE (2260 2060);
FORCEPROP 2 LASTPIN (2250 2000) $PN 250
J 0
(2260 2010);
DISPLAY 0.617021 (2260 2010);
PAINT ORANGE (2260 2010);
FORCEPROP 2 LASTPIN (2250 1950) $PN 252
J 0
(2260 1960);
DISPLAY 0.617021 (2260 1960);
PAINT ORANGE (2260 1960);
FORCEPROP 2 LASTPIN (2250 1900) $PN 254
J 0
(2260 1910);
DISPLAY 0.617021 (2260 1910);
PAINT ORANGE (2260 1910);
FORCEPROP 2 LASTPIN (2250 1850) $PN 257
J 0
(2260 1860);
DISPLAY 0.617021 (2260 1860);
PAINT ORANGE (2260 1860);
FORCEPROP 2 LASTPIN (2250 1800) $PN 259
J 0
(2260 1810);
DISPLAY 0.617021 (2260 1810);
PAINT ORANGE (2260 1810);
FORCEPROP 2 LASTPIN (2250 1750) $PN 261
J 0
(2260 1760);
DISPLAY 0.617021 (2260 1760);
PAINT ORANGE (2260 1760);
FORCEPROP 2 LASTPIN (2250 1700) $PN 263
J 0
(2260 1710);
DISPLAY 0.617021 (2260 1710);
PAINT ORANGE (2260 1710);
FORCEPROP 2 LASTPIN (2250 1650) $PN 265
J 0
(2260 1660);
DISPLAY 0.617021 (2260 1660);
PAINT ORANGE (2260 1660);
FORCEPROP 2 LASTPIN (2250 1600) $PN 268
J 0
(2260 1610);
DISPLAY 0.617021 (2260 1610);
PAINT ORANGE (2260 1610);
FORCEPROP 2 LASTPIN (2250 1550) $PN 270
J 0
(2260 1560);
DISPLAY 0.617021 (2260 1560);
PAINT ORANGE (2260 1560);
FORCEPROP 2 LASTPIN (2250 1500) $PN 272
J 0
(2260 1510);
DISPLAY 0.617021 (2260 1510);
PAINT ORANGE (2260 1510);
FORCEPROP 2 LASTPIN (2250 1450) $PN 274
J 0
(2260 1460);
DISPLAY 0.617021 (2260 1460);
PAINT ORANGE (2260 1460);
FORCEPROP 2 LASTPIN (2250 1400) $PN 276
J 0
(2260 1410);
DISPLAY 0.617021 (2260 1410);
PAINT ORANGE (2260 1410);
FORCEPROP 2 LASTPIN (2250 1350) $PN 279
J 0
(2260 1360);
DISPLAY 0.617021 (2260 1360);
PAINT ORANGE (2260 1360);
FORCEPROP 2 LASTPIN (2250 1300) $PN 281
J 0
(2260 1310);
DISPLAY 0.617021 (2260 1310);
PAINT ORANGE (2260 1310);
FORCEPROP 2 LASTPIN (2250 1250) $PN 283
J 0
(2260 1260);
DISPLAY 0.617021 (2260 1260);
PAINT ORANGE (2260 1260);
FORCEPROP 1 LAST PACK_TYPE PIP
J 0
(1300 3850);
PAINT SKYBLUE (1300 3850);
DISPLAY INVISIBLE (1300 3850);
FORCEPROP 2 LAST BOM_COST MEM
J 0
(1750 2400);
PAINT ORANGE (1750 2400);
DISPLAY INVISIBLE (1750 2400);
FORCEPROP 2 LAST CDS_LIB mstr_sconn
J 0
(1750 2400);
PAINT ORANGE (1750 2400);
DISPLAY INVISIBLE (1750 2400);
FORCEPROP 2 LAST SEC_TYPE PIP
J 0
(1300 3850);
DISPLAY 1.021277 (1300 3850);
PAINT ORANGE (1300 3850);
DISPLAY INVISIBLE (1300 3850);
FORCEPROP 2 LAST SEC 3
J 0
(1300 3850);
DISPLAY 0.680851 (1300 3850);
PAINT MONO (1300 3850);
DISPLAY INVISIBLE (1300 3850);
FORCEPROP 2 LAST CDS_LOCATION J4A1
J 0
(1300 3800);
DISPLAY 0.617021 (1300 3800);
PAINT AQUA (1300 3800);
DISPLAY INVISIBLE (1300 3800);
FORCEPROP 1 LAST PATH I43
J 0
(1750 3750);
PAINT GREEN (1750 3750);
DISPLAY INVISIBLE (1750 3750);
FORCEPROP 2 LAST ROOM DDR4_CH_F
J 0
(1750 2400);
PAINT ORANGE (1750 2400);
DISPLAY INVISIBLE (1750 2400);
FORCEADD GND..1
R 2
(1050 1075);
FORCEPROP 3 LASTPIN (1050 1125) SIG_NAME GND\g
J 0
(1060 1135);
DISPLAY 0.659574 (1060 1135);
PAINT MONO (1060 1135);
DISPLAY INVISIBLE (1060 1135);
FORCEPROP 1 LAST VOLTAGE 0
J 0
(1050 1075);
PAINT SKYBLUE (1050 1075);
DISPLAY INVISIBLE (1050 1075);
FORCEPROP 2 LAST BOM_COST MEM
J 0
(1050 1080);
PAINT ORANGE (1050 1080);
DISPLAY INVISIBLE (1050 1080);
FORCEPROP 1 LAST SIZE 1B
J 2
(975 1025);
DISPLAY 1.170213 (975 1025);
PAINT GREEN (975 1025);
DISPLAY INVISIBLE (975 1025);
FORCEPROP 2 LAST CDS_LIB mstr_symbols
J 0
(1050 1075);
DISPLAY 0.787234 (1050 1075);
PAINT MONO (1050 1075);
DISPLAY INVISIBLE (1050 1075);
FORCEPROP 1 LAST BODY_TYPE PLUMBING
J 2
(1095 1032);
DISPLAY 0.340426 (1095 1032);
PAINT GREEN (1095 1032);
DISPLAY INVISIBLE (1095 1032);
FORCEPROP 1 LAST PATH I44
J 2
(975 1075);
DISPLAY 0.936170 (975 1075);
PAINT GREEN (975 1075);
DISPLAY INVISIBLE (975 1075);
FORCEPROP 2 LAST ROOM DDR4_CH_C
J 0
(1050 1080);
PAINT ORANGE (1050 1080);
DISPLAY INVISIBLE (1050 1080);
FORCEPROP 1 LAST HDL_POWER GND
J 2
(1050 1225);
DISPLAY 0.553191 (1050 1225);
PAINT GREEN (1050 1225);
DISPLAY INVISIBLE (1050 1225);
FORCEADD OFFPAGE..3
(-1000 4525);
FORCEPROP 2 LAST $XR0 28 
J 0
(-786 4525);
DISPLAY 0.638298 (-786 4525);
PAINT MONO (-786 4525);
FORCEPROP 2 LAST $XR1 54 
J 0
(-696 4525);
DISPLAY 0.638298 (-696 4525);
PAINT MONO (-696 4525);
FORCEPROP 2 LAST CDS_LIB mstr_standard
J 0
(-1000 4525);
DISPLAY 0.787234 (-1000 4525);
PAINT MONO (-1000 4525);
DISPLAY INVISIBLE (-1000 4525);
FORCEPROP 1 LAST OFFPAGE TRUE
J 0
(-675 4400);
DISPLAY 0.936170 (-675 4400);
PAINT GREEN (-675 4400);
DISPLAY INVISIBLE (-675 4400);
FORCEPROP 1 LAST COMMENT_BODY TRUE
J 0
(-1050 4425);
DISPLAY 0.936170 (-1050 4425);
PAINT GREEN (-1050 4425);
DISPLAY INVISIBLE (-1050 4425);
FORCEPROP 2 LAST PATH I45
J 0
(-800 4600);
DISPLAY 0.787234 (-800 4600);
PAINT MONO (-800 4600);
DISPLAY INVISIBLE (-800 4600);
FORCEADD TAP..6
R 2
(-1550 4475);
FORCEPROP 3 LASTPIN (-1600 4475) SIG_NAME M_F_DQ<62>
J 0
(-1590 4485);
DISPLAY 0.659574 (-1590 4485);
PAINT MONO (-1590 4485);
DISPLAY INVISIBLE (-1590 4485);
FORCEPROP 1 LASTPIN (-1600 4475) BN 62
J 2
(-1550 4485);
DISPLAY 0.617021 (-1550 4485);
PAINT PINK (-1550 4485);
FORCEPROP 2 LAST CDS_LIB mstr_standard
J 2
(-1550 4475);
DISPLAY 0.787234 (-1550 4475);
PAINT MONO (-1550 4475);
DISPLAY INVISIBLE (-1550 4475);
FORCEPROP 1 LAST BODY_TYPE PLUMBING
J 2
(-1550 4425);
DISPLAY 1.234043 (-1550 4425);
PAINT GREEN (-1550 4425);
DISPLAY INVISIBLE (-1550 4425);
FORCEPROP 1 LAST HDL_TAP TRUE
J 2
(-1875 4350);
DISPLAY 1.234043 (-1875 4350);
PAINT GREEN (-1875 4350);
DISPLAY INVISIBLE (-1875 4350);
FORCEPROP 1 LAST PATH I46
J 2
(-1550 4475);
DISPLAY 0.936170 (-1550 4475);
PAINT GREEN (-1550 4475);
DISPLAY INVISIBLE (-1550 4475);
FORCEADD TAP..6
R 2
(-1550 4425);
FORCEPROP 3 LASTPIN (-1600 4425) SIG_NAME M_F_DQ<63>
J 0
(-1590 4435);
DISPLAY 0.659574 (-1590 4435);
PAINT MONO (-1590 4435);
DISPLAY INVISIBLE (-1590 4435);
FORCEPROP 1 LASTPIN (-1600 4425) BN 63
J 2
(-1550 4435);
DISPLAY 0.617021 (-1550 4435);
PAINT PINK (-1550 4435);
FORCEPROP 2 LAST CDS_LIB mstr_standard
J 2
(-1550 4425);
DISPLAY 0.787234 (-1550 4425);
PAINT MONO (-1550 4425);
DISPLAY INVISIBLE (-1550 4425);
FORCEPROP 1 LAST BODY_TYPE PLUMBING
J 2
(-1550 4375);
DISPLAY 1.234043 (-1550 4375);
PAINT GREEN (-1550 4375);
DISPLAY INVISIBLE (-1550 4375);
FORCEPROP 1 LAST HDL_TAP TRUE
J 2
(-1875 4300);
DISPLAY 1.234043 (-1875 4300);
PAINT GREEN (-1875 4300);
DISPLAY INVISIBLE (-1875 4300);
FORCEPROP 1 LAST PATH I47
J 2
(-1550 4425);
DISPLAY 0.936170 (-1550 4425);
PAINT GREEN (-1550 4425);
DISPLAY INVISIBLE (-1550 4425);
FORCEADD TAP..6
R 2
(-1550 4325);
FORCEPROP 3 LASTPIN (-1600 4325) SIG_NAME M_F_DQ<61>
J 0
(-1590 4335);
DISPLAY 0.659574 (-1590 4335);
PAINT MONO (-1590 4335);
DISPLAY INVISIBLE (-1590 4335);
FORCEPROP 1 LASTPIN (-1600 4325) BN 61
J 2
(-1550 4335);
DISPLAY 0.617021 (-1550 4335);
PAINT PINK (-1550 4335);
FORCEPROP 2 LAST CDS_LIB mstr_standard
J 2
(-1550 4325);
DISPLAY 0.787234 (-1550 4325);
PAINT MONO (-1550 4325);
DISPLAY INVISIBLE (-1550 4325);
FORCEPROP 1 LAST BODY_TYPE PLUMBING
J 2
(-1550 4275);
DISPLAY 1.234043 (-1550 4275);
PAINT GREEN (-1550 4275);
DISPLAY INVISIBLE (-1550 4275);
FORCEPROP 1 LAST HDL_TAP TRUE
J 2
(-1875 4200);
DISPLAY 1.234043 (-1875 4200);
PAINT GREEN (-1875 4200);
DISPLAY INVISIBLE (-1875 4200);
FORCEPROP 1 LAST PATH I48
J 2
(-1550 4325);
DISPLAY 0.936170 (-1550 4325);
PAINT GREEN (-1550 4325);
DISPLAY INVISIBLE (-1550 4325);
FORCEADD TAP..6
R 2
(-1550 4375);
FORCEPROP 3 LASTPIN (-1600 4375) SIG_NAME M_F_DQ<60>
J 0
(-1590 4385);
DISPLAY 0.659574 (-1590 4385);
PAINT MONO (-1590 4385);
DISPLAY INVISIBLE (-1590 4385);
FORCEPROP 1 LASTPIN (-1600 4375) BN 60
J 2
(-1550 4385);
DISPLAY 0.617021 (-1550 4385);
PAINT PINK (-1550 4385);
FORCEPROP 2 LAST CDS_LIB mstr_standard
J 2
(-1550 4375);
DISPLAY 0.787234 (-1550 4375);
PAINT MONO (-1550 4375);
DISPLAY INVISIBLE (-1550 4375);
FORCEPROP 1 LAST BODY_TYPE PLUMBING
J 2
(-1550 4325);
DISPLAY 1.234043 (-1550 4325);
PAINT GREEN (-1550 4325);
DISPLAY INVISIBLE (-1550 4325);
FORCEPROP 1 LAST HDL_TAP TRUE
J 2
(-1875 4250);
DISPLAY 1.234043 (-1875 4250);
PAINT GREEN (-1875 4250);
DISPLAY INVISIBLE (-1875 4250);
FORCEPROP 1 LAST PATH I49
J 2
(-1550 4375);
DISPLAY 0.936170 (-1550 4375);
PAINT GREEN (-1550 4375);
DISPLAY INVISIBLE (-1550 4375);
FORCEADD TAP..6
R 2
(850 5050);
FORCEPROP 3 LASTPIN (800 5050) SIG_NAME M_F_DQS_DN<16>
J 0
(810 5060);
DISPLAY 0.659574 (810 5060);
PAINT MONO (810 5060);
DISPLAY INVISIBLE (810 5060);
FORCEPROP 1 LASTPIN (800 5050) BN 16
J 2
(850 5060);
DISPLAY 0.617021 (850 5060);
PAINT PINK (850 5060);
FORCEPROP 2 LAST CDS_LIB mstr_standard
J 0
(850 5050);
DISPLAY 0.787234 (850 5050);
PAINT MONO (850 5050);
DISPLAY INVISIBLE (850 5050);
FORCEPROP 1 LAST BODY_TYPE PLUMBING
J 2
(850 5000);
DISPLAY 1.234043 (850 5000);
PAINT GREEN (850 5000);
DISPLAY INVISIBLE (850 5000);
FORCEPROP 1 LAST HDL_TAP TRUE
J 2
(525 4925);
DISPLAY 1.234043 (525 4925);
PAINT GREEN (525 4925);
DISPLAY INVISIBLE (525 4925);
FORCEPROP 1 LAST PATH I5
J 2
(850 5050);
DISPLAY 0.936170 (850 5050);
PAINT GREEN (850 5050);
DISPLAY INVISIBLE (850 5050);
FORCEADD TAP..6
R 2
(-1550 4275);
FORCEPROP 3 LASTPIN (-1600 4275) SIG_NAME M_F_DQ<58>
J 0
(-1590 4285);
DISPLAY 0.659574 (-1590 4285);
PAINT MONO (-1590 4285);
DISPLAY INVISIBLE (-1590 4285);
FORCEPROP 1 LASTPIN (-1600 4275) BN 58
J 2
(-1550 4285);
DISPLAY 0.617021 (-1550 4285);
PAINT PINK (-1550 4285);
FORCEPROP 2 LAST CDS_LIB mstr_standard
J 2
(-1550 4275);
DISPLAY 0.787234 (-1550 4275);
PAINT MONO (-1550 4275);
DISPLAY INVISIBLE (-1550 4275);
FORCEPROP 1 LAST BODY_TYPE PLUMBING
J 2
(-1550 4225);
DISPLAY 1.234043 (-1550 4225);
PAINT GREEN (-1550 4225);
DISPLAY INVISIBLE (-1550 4225);
FORCEPROP 1 LAST HDL_TAP TRUE
J 2
(-1875 4150);
DISPLAY 1.234043 (-1875 4150);
PAINT GREEN (-1875 4150);
DISPLAY INVISIBLE (-1875 4150);
FORCEPROP 1 LAST PATH I50
J 2
(-1550 4275);
DISPLAY 0.936170 (-1550 4275);
PAINT GREEN (-1550 4275);
DISPLAY INVISIBLE (-1550 4275);
FORCEADD TAP..6
R 2
(-1550 4175);
FORCEPROP 3 LASTPIN (-1600 4175) SIG_NAME M_F_DQ<56>
J 0
(-1590 4185);
DISPLAY 0.659574 (-1590 4185);
PAINT MONO (-1590 4185);
DISPLAY INVISIBLE (-1590 4185);
FORCEPROP 1 LASTPIN (-1600 4175) BN 56
J 2
(-1550 4185);
DISPLAY 0.617021 (-1550 4185);
PAINT PINK (-1550 4185);
FORCEPROP 2 LAST CDS_LIB mstr_standard
J 2
(-1550 4175);
DISPLAY 0.787234 (-1550 4175);
PAINT MONO (-1550 4175);
DISPLAY INVISIBLE (-1550 4175);
FORCEPROP 1 LAST BODY_TYPE PLUMBING
J 2
(-1550 4125);
DISPLAY 1.234043 (-1550 4125);
PAINT GREEN (-1550 4125);
DISPLAY INVISIBLE (-1550 4125);
FORCEPROP 1 LAST HDL_TAP TRUE
J 2
(-1875 4050);
DISPLAY 1.234043 (-1875 4050);
PAINT GREEN (-1875 4050);
DISPLAY INVISIBLE (-1875 4050);
FORCEPROP 1 LAST PATH I51
J 2
(-1550 4175);
DISPLAY 0.936170 (-1550 4175);
PAINT GREEN (-1550 4175);
DISPLAY INVISIBLE (-1550 4175);
FORCEADD TAP..6
R 2
(-1550 4225);
FORCEPROP 3 LASTPIN (-1600 4225) SIG_NAME M_F_DQ<59>
J 0
(-1590 4235);
DISPLAY 0.659574 (-1590 4235);
PAINT MONO (-1590 4235);
DISPLAY INVISIBLE (-1590 4235);
FORCEPROP 1 LASTPIN (-1600 4225) BN 59
J 2
(-1550 4235);
DISPLAY 0.617021 (-1550 4235);
PAINT PINK (-1550 4235);
FORCEPROP 2 LAST CDS_LIB mstr_standard
J 2
(-1550 4225);
DISPLAY 0.787234 (-1550 4225);
PAINT MONO (-1550 4225);
DISPLAY INVISIBLE (-1550 4225);
FORCEPROP 1 LAST BODY_TYPE PLUMBING
J 2
(-1550 4175);
DISPLAY 1.234043 (-1550 4175);
PAINT GREEN (-1550 4175);
DISPLAY INVISIBLE (-1550 4175);
FORCEPROP 1 LAST HDL_TAP TRUE
J 2
(-1875 4100);
DISPLAY 1.234043 (-1875 4100);
PAINT GREEN (-1875 4100);
DISPLAY INVISIBLE (-1875 4100);
FORCEPROP 1 LAST PATH I52
J 2
(-1550 4225);
DISPLAY 0.936170 (-1550 4225);
PAINT GREEN (-1550 4225);
DISPLAY INVISIBLE (-1550 4225);
FORCEADD TAP..6
R 2
(-1550 4125);
FORCEPROP 3 LASTPIN (-1600 4125) SIG_NAME M_F_DQ<57>
J 0
(-1590 4135);
DISPLAY 0.659574 (-1590 4135);
PAINT MONO (-1590 4135);
DISPLAY INVISIBLE (-1590 4135);
FORCEPROP 1 LASTPIN (-1600 4125) BN 57
J 2
(-1550 4135);
DISPLAY 0.617021 (-1550 4135);
PAINT PINK (-1550 4135);
FORCEPROP 2 LAST CDS_LIB mstr_standard
J 2
(-1550 4125);
DISPLAY 0.787234 (-1550 4125);
PAINT MONO (-1550 4125);
DISPLAY INVISIBLE (-1550 4125);
FORCEPROP 1 LAST BODY_TYPE PLUMBING
J 2
(-1550 4075);
DISPLAY 1.234043 (-1550 4075);
PAINT GREEN (-1550 4075);
DISPLAY INVISIBLE (-1550 4075);
FORCEPROP 1 LAST HDL_TAP TRUE
J 2
(-1875 4000);
DISPLAY 1.234043 (-1875 4000);
PAINT GREEN (-1875 4000);
DISPLAY INVISIBLE (-1875 4000);
FORCEPROP 1 LAST PATH I53
J 2
(-1550 4125);
DISPLAY 0.936170 (-1550 4125);
PAINT GREEN (-1550 4125);
DISPLAY INVISIBLE (-1550 4125);
FORCEADD TAP..6
R 2
(-1550 4075);
FORCEPROP 3 LASTPIN (-1600 4075) SIG_NAME M_F_DQ<54>
J 0
(-1590 4085);
DISPLAY 0.659574 (-1590 4085);
PAINT MONO (-1590 4085);
DISPLAY INVISIBLE (-1590 4085);
FORCEPROP 1 LASTPIN (-1600 4075) BN 54
J 2
(-1550 4085);
DISPLAY 0.617021 (-1550 4085);
PAINT PINK (-1550 4085);
FORCEPROP 2 LAST CDS_LIB mstr_standard
J 2
(-1550 4075);
DISPLAY 0.787234 (-1550 4075);
PAINT MONO (-1550 4075);
DISPLAY INVISIBLE (-1550 4075);
FORCEPROP 1 LAST BODY_TYPE PLUMBING
J 2
(-1550 4025);
DISPLAY 1.234043 (-1550 4025);
PAINT GREEN (-1550 4025);
DISPLAY INVISIBLE (-1550 4025);
FORCEPROP 1 LAST HDL_TAP TRUE
J 2
(-1875 3950);
DISPLAY 1.234043 (-1875 3950);
PAINT GREEN (-1875 3950);
DISPLAY INVISIBLE (-1875 3950);
FORCEPROP 1 LAST PATH I54
J 2
(-1550 4075);
DISPLAY 0.936170 (-1550 4075);
PAINT GREEN (-1550 4075);
DISPLAY INVISIBLE (-1550 4075);
FORCEADD TAP..6
R 2
(-1550 3975);
FORCEPROP 3 LASTPIN (-1600 3975) SIG_NAME M_F_DQ<52>
J 0
(-1590 3985);
DISPLAY 0.659574 (-1590 3985);
PAINT MONO (-1590 3985);
DISPLAY INVISIBLE (-1590 3985);
FORCEPROP 1 LASTPIN (-1600 3975) BN 52
J 2
(-1550 3985);
DISPLAY 0.617021 (-1550 3985);
PAINT PINK (-1550 3985);
FORCEPROP 2 LAST CDS_LIB mstr_standard
J 2
(-1550 3975);
DISPLAY 0.787234 (-1550 3975);
PAINT MONO (-1550 3975);
DISPLAY INVISIBLE (-1550 3975);
FORCEPROP 1 LAST BODY_TYPE PLUMBING
J 2
(-1550 3925);
DISPLAY 1.234043 (-1550 3925);
PAINT GREEN (-1550 3925);
DISPLAY INVISIBLE (-1550 3925);
FORCEPROP 1 LAST HDL_TAP TRUE
J 2
(-1875 3850);
DISPLAY 1.234043 (-1875 3850);
PAINT GREEN (-1875 3850);
DISPLAY INVISIBLE (-1875 3850);
FORCEPROP 1 LAST PATH I55
J 2
(-1550 3975);
DISPLAY 0.936170 (-1550 3975);
PAINT GREEN (-1550 3975);
DISPLAY INVISIBLE (-1550 3975);
FORCEADD TAP..6
R 2
(-1550 4025);
FORCEPROP 3 LASTPIN (-1600 4025) SIG_NAME M_F_DQ<55>
J 0
(-1590 4035);
DISPLAY 0.659574 (-1590 4035);
PAINT MONO (-1590 4035);
DISPLAY INVISIBLE (-1590 4035);
FORCEPROP 1 LASTPIN (-1600 4025) BN 55
J 2
(-1550 4035);
DISPLAY 0.617021 (-1550 4035);
PAINT PINK (-1550 4035);
FORCEPROP 2 LAST CDS_LIB mstr_standard
J 2
(-1550 4025);
DISPLAY 0.787234 (-1550 4025);
PAINT MONO (-1550 4025);
DISPLAY INVISIBLE (-1550 4025);
FORCEPROP 1 LAST BODY_TYPE PLUMBING
J 2
(-1550 3975);
DISPLAY 1.234043 (-1550 3975);
PAINT GREEN (-1550 3975);
DISPLAY INVISIBLE (-1550 3975);
FORCEPROP 1 LAST HDL_TAP TRUE
J 2
(-1875 3900);
DISPLAY 1.234043 (-1875 3900);
PAINT GREEN (-1875 3900);
DISPLAY INVISIBLE (-1875 3900);
FORCEPROP 1 LAST PATH I56
J 2
(-1550 4025);
DISPLAY 0.936170 (-1550 4025);
PAINT GREEN (-1550 4025);
DISPLAY INVISIBLE (-1550 4025);
FORCEADD TAP..6
R 2
(-1550 3925);
FORCEPROP 3 LASTPIN (-1600 3925) SIG_NAME M_F_DQ<53>
J 0
(-1590 3935);
DISPLAY 0.659574 (-1590 3935);
PAINT MONO (-1590 3935);
DISPLAY INVISIBLE (-1590 3935);
FORCEPROP 1 LASTPIN (-1600 3925) BN 53
J 2
(-1550 3935);
DISPLAY 0.617021 (-1550 3935);
PAINT PINK (-1550 3935);
FORCEPROP 2 LAST CDS_LIB mstr_standard
J 2
(-1550 3925);
DISPLAY 0.787234 (-1550 3925);
PAINT MONO (-1550 3925);
DISPLAY INVISIBLE (-1550 3925);
FORCEPROP 1 LAST BODY_TYPE PLUMBING
J 2
(-1550 3875);
DISPLAY 1.234043 (-1550 3875);
PAINT GREEN (-1550 3875);
DISPLAY INVISIBLE (-1550 3875);
FORCEPROP 1 LAST HDL_TAP TRUE
J 2
(-1875 3800);
DISPLAY 1.234043 (-1875 3800);
PAINT GREEN (-1875 3800);
DISPLAY INVISIBLE (-1875 3800);
FORCEPROP 1 LAST PATH I57
J 2
(-1550 3925);
DISPLAY 0.936170 (-1550 3925);
PAINT GREEN (-1550 3925);
DISPLAY INVISIBLE (-1550 3925);
FORCEADD TAP..6
R 2
(-1550 3875);
FORCEPROP 3 LASTPIN (-1600 3875) SIG_NAME M_F_DQ<50>
J 0
(-1590 3885);
DISPLAY 0.659574 (-1590 3885);
PAINT MONO (-1590 3885);
DISPLAY INVISIBLE (-1590 3885);
FORCEPROP 1 LASTPIN (-1600 3875) BN 50
J 2
(-1550 3885);
DISPLAY 0.617021 (-1550 3885);
PAINT PINK (-1550 3885);
FORCEPROP 2 LAST CDS_LIB mstr_standard
J 2
(-1550 3875);
DISPLAY 0.787234 (-1550 3875);
PAINT MONO (-1550 3875);
DISPLAY INVISIBLE (-1550 3875);
FORCEPROP 1 LAST BODY_TYPE PLUMBING
J 2
(-1550 3825);
DISPLAY 1.234043 (-1550 3825);
PAINT GREEN (-1550 3825);
DISPLAY INVISIBLE (-1550 3825);
FORCEPROP 1 LAST HDL_TAP TRUE
J 2
(-1875 3750);
DISPLAY 1.234043 (-1875 3750);
PAINT GREEN (-1875 3750);
DISPLAY INVISIBLE (-1875 3750);
FORCEPROP 1 LAST PATH I58
J 2
(-1550 3875);
DISPLAY 0.936170 (-1550 3875);
PAINT GREEN (-1550 3875);
DISPLAY INVISIBLE (-1550 3875);
FORCEADD TAP..6
R 2
(-1550 3825);
FORCEPROP 3 LASTPIN (-1600 3825) SIG_NAME M_F_DQ<51>
J 0
(-1590 3835);
DISPLAY 0.659574 (-1590 3835);
PAINT MONO (-1590 3835);
DISPLAY INVISIBLE (-1590 3835);
FORCEPROP 1 LASTPIN (-1600 3825) BN 51
J 2
(-1550 3835);
DISPLAY 0.617021 (-1550 3835);
PAINT PINK (-1550 3835);
FORCEPROP 2 LAST CDS_LIB mstr_standard
J 2
(-1550 3825);
DISPLAY 0.787234 (-1550 3825);
PAINT MONO (-1550 3825);
DISPLAY INVISIBLE (-1550 3825);
FORCEPROP 1 LAST BODY_TYPE PLUMBING
J 2
(-1550 3775);
DISPLAY 1.234043 (-1550 3775);
PAINT GREEN (-1550 3775);
DISPLAY INVISIBLE (-1550 3775);
FORCEPROP 1 LAST HDL_TAP TRUE
J 2
(-1875 3700);
DISPLAY 1.234043 (-1875 3700);
PAINT GREEN (-1875 3700);
DISPLAY INVISIBLE (-1875 3700);
FORCEPROP 1 LAST PATH I59
J 2
(-1550 3825);
DISPLAY 0.936170 (-1550 3825);
PAINT GREEN (-1550 3825);
DISPLAY INVISIBLE (-1550 3825);
FORCEADD TAP..6
R 2
(850 4950);
FORCEPROP 3 LASTPIN (800 4950) SIG_NAME M_F_DQS_DN<15>
J 0
(810 4960);
DISPLAY 0.659574 (810 4960);
PAINT MONO (810 4960);
DISPLAY INVISIBLE (810 4960);
FORCEPROP 1 LASTPIN (800 4950) BN 15
J 2
(850 4960);
DISPLAY 0.617021 (850 4960);
PAINT PINK (850 4960);
FORCEPROP 2 LAST CDS_LIB mstr_standard
J 0
(850 4950);
DISPLAY 0.787234 (850 4950);
PAINT MONO (850 4950);
DISPLAY INVISIBLE (850 4950);
FORCEPROP 1 LAST BODY_TYPE PLUMBING
J 2
(850 4900);
DISPLAY 1.234043 (850 4900);
PAINT GREEN (850 4900);
DISPLAY INVISIBLE (850 4900);
FORCEPROP 1 LAST HDL_TAP TRUE
J 2
(525 4825);
DISPLAY 1.234043 (525 4825);
PAINT GREEN (525 4825);
DISPLAY INVISIBLE (525 4825);
FORCEPROP 1 LAST PATH I6
J 2
(850 4950);
DISPLAY 0.936170 (850 4950);
PAINT GREEN (850 4950);
DISPLAY INVISIBLE (850 4950);
FORCEADD TAP..6
R 2
(-1550 3775);
FORCEPROP 3 LASTPIN (-1600 3775) SIG_NAME M_F_DQ<48>
J 0
(-1590 3785);
DISPLAY 0.659574 (-1590 3785);
PAINT MONO (-1590 3785);
DISPLAY INVISIBLE (-1590 3785);
FORCEPROP 1 LASTPIN (-1600 3775) BN 48
J 2
(-1550 3785);
DISPLAY 0.617021 (-1550 3785);
PAINT PINK (-1550 3785);
FORCEPROP 2 LAST CDS_LIB mstr_standard
J 2
(-1550 3775);
DISPLAY 0.787234 (-1550 3775);
PAINT MONO (-1550 3775);
DISPLAY INVISIBLE (-1550 3775);
FORCEPROP 1 LAST BODY_TYPE PLUMBING
J 2
(-1550 3725);
DISPLAY 1.234043 (-1550 3725);
PAINT GREEN (-1550 3725);
DISPLAY INVISIBLE (-1550 3725);
FORCEPROP 1 LAST HDL_TAP TRUE
J 2
(-1875 3650);
DISPLAY 1.234043 (-1875 3650);
PAINT GREEN (-1875 3650);
DISPLAY INVISIBLE (-1875 3650);
FORCEPROP 1 LAST PATH I60
J 2
(-1550 3775);
DISPLAY 0.936170 (-1550 3775);
PAINT GREEN (-1550 3775);
DISPLAY INVISIBLE (-1550 3775);
FORCEADD TAP..6
R 2
(-1550 3675);
FORCEPROP 3 LASTPIN (-1600 3675) SIG_NAME M_F_DQ<46>
J 0
(-1590 3685);
DISPLAY 0.659574 (-1590 3685);
PAINT MONO (-1590 3685);
DISPLAY INVISIBLE (-1590 3685);
FORCEPROP 1 LASTPIN (-1600 3675) BN 46
J 2
(-1550 3685);
DISPLAY 0.617021 (-1550 3685);
PAINT PINK (-1550 3685);
FORCEPROP 2 LAST CDS_LIB mstr_standard
J 2
(-1550 3675);
DISPLAY 0.787234 (-1550 3675);
PAINT MONO (-1550 3675);
DISPLAY INVISIBLE (-1550 3675);
FORCEPROP 1 LAST BODY_TYPE PLUMBING
J 2
(-1550 3625);
DISPLAY 1.234043 (-1550 3625);
PAINT GREEN (-1550 3625);
DISPLAY INVISIBLE (-1550 3625);
FORCEPROP 1 LAST HDL_TAP TRUE
J 2
(-1875 3550);
DISPLAY 1.234043 (-1875 3550);
PAINT GREEN (-1875 3550);
DISPLAY INVISIBLE (-1875 3550);
FORCEPROP 1 LAST PATH I61
J 2
(-1550 3675);
DISPLAY 0.936170 (-1550 3675);
PAINT GREEN (-1550 3675);
DISPLAY INVISIBLE (-1550 3675);
FORCEADD TAP..6
R 2
(-1550 3725);
FORCEPROP 3 LASTPIN (-1600 3725) SIG_NAME M_F_DQ<49>
J 0
(-1590 3735);
DISPLAY 0.659574 (-1590 3735);
PAINT MONO (-1590 3735);
DISPLAY INVISIBLE (-1590 3735);
FORCEPROP 1 LASTPIN (-1600 3725) BN 49
J 2
(-1550 3735);
DISPLAY 0.617021 (-1550 3735);
PAINT PINK (-1550 3735);
FORCEPROP 2 LAST CDS_LIB mstr_standard
J 2
(-1550 3725);
DISPLAY 0.787234 (-1550 3725);
PAINT MONO (-1550 3725);
DISPLAY INVISIBLE (-1550 3725);
FORCEPROP 1 LAST BODY_TYPE PLUMBING
J 2
(-1550 3675);
DISPLAY 1.234043 (-1550 3675);
PAINT GREEN (-1550 3675);
DISPLAY INVISIBLE (-1550 3675);
FORCEPROP 1 LAST HDL_TAP TRUE
J 2
(-1875 3600);
DISPLAY 1.234043 (-1875 3600);
PAINT GREEN (-1875 3600);
DISPLAY INVISIBLE (-1875 3600);
FORCEPROP 1 LAST PATH I62
J 2
(-1550 3725);
DISPLAY 0.936170 (-1550 3725);
PAINT GREEN (-1550 3725);
DISPLAY INVISIBLE (-1550 3725);
FORCEADD TAP..6
R 2
(-1550 3625);
FORCEPROP 3 LASTPIN (-1600 3625) SIG_NAME M_F_DQ<47>
J 0
(-1590 3635);
DISPLAY 0.659574 (-1590 3635);
PAINT MONO (-1590 3635);
DISPLAY INVISIBLE (-1590 3635);
FORCEPROP 1 LASTPIN (-1600 3625) BN 47
J 2
(-1550 3635);
DISPLAY 0.617021 (-1550 3635);
PAINT PINK (-1550 3635);
FORCEPROP 2 LAST CDS_LIB mstr_standard
J 2
(-1550 3625);
DISPLAY 0.787234 (-1550 3625);
PAINT MONO (-1550 3625);
DISPLAY INVISIBLE (-1550 3625);
FORCEPROP 1 LAST BODY_TYPE PLUMBING
J 2
(-1550 3575);
DISPLAY 1.234043 (-1550 3575);
PAINT GREEN (-1550 3575);
DISPLAY INVISIBLE (-1550 3575);
FORCEPROP 1 LAST HDL_TAP TRUE
J 2
(-1875 3500);
DISPLAY 1.234043 (-1875 3500);
PAINT GREEN (-1875 3500);
DISPLAY INVISIBLE (-1875 3500);
FORCEPROP 1 LAST PATH I63
J 2
(-1550 3625);
DISPLAY 0.936170 (-1550 3625);
PAINT GREEN (-1550 3625);
DISPLAY INVISIBLE (-1550 3625);
FORCEADD TAP..6
R 2
(-1550 3575);
FORCEPROP 3 LASTPIN (-1600 3575) SIG_NAME M_F_DQ<44>
J 0
(-1590 3585);
DISPLAY 0.659574 (-1590 3585);
PAINT MONO (-1590 3585);
DISPLAY INVISIBLE (-1590 3585);
FORCEPROP 1 LASTPIN (-1600 3575) BN 44
J 2
(-1550 3585);
DISPLAY 0.617021 (-1550 3585);
PAINT PINK (-1550 3585);
FORCEPROP 2 LAST CDS_LIB mstr_standard
J 2
(-1550 3575);
DISPLAY 0.787234 (-1550 3575);
PAINT MONO (-1550 3575);
DISPLAY INVISIBLE (-1550 3575);
FORCEPROP 1 LAST BODY_TYPE PLUMBING
J 2
(-1550 3525);
DISPLAY 1.234043 (-1550 3525);
PAINT GREEN (-1550 3525);
DISPLAY INVISIBLE (-1550 3525);
FORCEPROP 1 LAST HDL_TAP TRUE
J 2
(-1875 3450);
DISPLAY 1.234043 (-1875 3450);
PAINT GREEN (-1875 3450);
DISPLAY INVISIBLE (-1875 3450);
FORCEPROP 1 LAST PATH I64
J 2
(-1550 3575);
DISPLAY 0.936170 (-1550 3575);
PAINT GREEN (-1550 3575);
DISPLAY INVISIBLE (-1550 3575);
FORCEADD TAP..6
R 2
(-1550 3525);
FORCEPROP 3 LASTPIN (-1600 3525) SIG_NAME M_F_DQ<45>
J 0
(-1590 3535);
DISPLAY 0.659574 (-1590 3535);
PAINT MONO (-1590 3535);
DISPLAY INVISIBLE (-1590 3535);
FORCEPROP 1 LASTPIN (-1600 3525) BN 45
J 2
(-1550 3535);
DISPLAY 0.617021 (-1550 3535);
PAINT PINK (-1550 3535);
FORCEPROP 2 LAST CDS_LIB mstr_standard
J 2
(-1550 3525);
DISPLAY 0.787234 (-1550 3525);
PAINT MONO (-1550 3525);
DISPLAY INVISIBLE (-1550 3525);
FORCEPROP 1 LAST BODY_TYPE PLUMBING
J 2
(-1550 3475);
DISPLAY 1.234043 (-1550 3475);
PAINT GREEN (-1550 3475);
DISPLAY INVISIBLE (-1550 3475);
FORCEPROP 1 LAST HDL_TAP TRUE
J 2
(-1875 3400);
DISPLAY 1.234043 (-1875 3400);
PAINT GREEN (-1875 3400);
DISPLAY INVISIBLE (-1875 3400);
FORCEPROP 1 LAST PATH I65
J 2
(-1550 3525);
DISPLAY 0.936170 (-1550 3525);
PAINT GREEN (-1550 3525);
DISPLAY INVISIBLE (-1550 3525);
FORCEADD SCONN288_H44441004..2
(-50 4350);
FORCEPROP 1 LAST LOCATION J4A1
J 0
(-450 5450);
DISPLAY 0.617021 (-450 5450);
PAINT AQUA (-450 5450);
FORCEPROP 1 LAST PART_NUMBER H44441-004
J 0
(-450 3250);
DISPLAY 0.617021 (-450 3250);
PAINT BLUE (-450 3250);
FORCEPROP 1 LAST MATERIAL SCONN
J 0
(-450 5400);
DISPLAY 0.617021 (-450 5400);
PAINT SKYBLUE (-450 5400);
FORCEPROP 2 LASTPIN (400 5200) $PN 51
J 0
(410 5210);
DISPLAY 0.617021 (410 5210);
PAINT ORANGE (410 5210);
FORCEPROP 2 LASTPIN (400 5150) $PN 52
J 0
(410 5160);
DISPLAY 0.617021 (410 5160);
PAINT ORANGE (410 5160);
FORCEPROP 2 LASTPIN (400 5100) $PN 132
J 0
(410 5110);
DISPLAY 0.617021 (410 5110);
PAINT ORANGE (410 5110);
FORCEPROP 2 LASTPIN (400 5050) $PN 133
J 0
(410 5060);
DISPLAY 0.617021 (410 5060);
PAINT ORANGE (410 5060);
FORCEPROP 2 LASTPIN (400 5000) $PN 121
J 0
(410 5010);
DISPLAY 0.617021 (410 5010);
PAINT ORANGE (410 5010);
FORCEPROP 2 LASTPIN (400 4950) $PN 122
J 0
(410 4960);
DISPLAY 0.617021 (410 4960);
PAINT ORANGE (410 4960);
FORCEPROP 2 LASTPIN (400 4900) $PN 110
J 0
(410 4910);
DISPLAY 0.617021 (410 4910);
PAINT ORANGE (410 4910);
FORCEPROP 2 LASTPIN (400 4850) $PN 111
J 0
(410 4860);
DISPLAY 0.617021 (410 4860);
PAINT ORANGE (410 4860);
FORCEPROP 2 LASTPIN (400 4800) $PN 99
J 0
(410 4810);
DISPLAY 0.617021 (410 4810);
PAINT ORANGE (410 4810);
FORCEPROP 2 LASTPIN (400 4750) $PN 100
J 0
(410 4760);
DISPLAY 0.617021 (410 4760);
PAINT ORANGE (410 4760);
FORCEPROP 2 LASTPIN (400 4700) $PN 40
J 0
(410 4710);
DISPLAY 0.617021 (410 4710);
PAINT ORANGE (410 4710);
FORCEPROP 2 LASTPIN (400 4650) $PN 41
J 0
(410 4660);
DISPLAY 0.617021 (410 4660);
PAINT ORANGE (410 4660);
FORCEPROP 2 LASTPIN (400 4600) $PN 29
J 0
(410 4610);
DISPLAY 0.617021 (410 4610);
PAINT ORANGE (410 4610);
FORCEPROP 2 LASTPIN (400 4550) $PN 30
J 0
(410 4560);
DISPLAY 0.617021 (410 4560);
PAINT ORANGE (410 4560);
FORCEPROP 2 LASTPIN (400 4500) $PN 18
J 0
(410 4510);
DISPLAY 0.617021 (410 4510);
PAINT ORANGE (410 4510);
FORCEPROP 2 LASTPIN (400 4450) $PN 19
J 0
(410 4460);
DISPLAY 0.617021 (410 4460);
PAINT ORANGE (410 4460);
FORCEPROP 2 LASTPIN (400 4400) $PN 7
J 0
(410 4410);
DISPLAY 0.617021 (410 4410);
PAINT ORANGE (410 4410);
FORCEPROP 2 LASTPIN (400 4350) $PN 8
J 0
(410 4360);
DISPLAY 0.617021 (410 4360);
PAINT ORANGE (410 4360);
FORCEPROP 2 LASTPIN (400 4300) $PN 197
J 0
(410 4310);
DISPLAY 0.617021 (410 4310);
PAINT ORANGE (410 4310);
FORCEPROP 2 LASTPIN (400 4250) $PN 196
J 0
(410 4260);
DISPLAY 0.617021 (410 4260);
PAINT ORANGE (410 4260);
FORCEPROP 2 LASTPIN (400 4200) $PN 278
J 0
(410 4210);
DISPLAY 0.617021 (410 4210);
PAINT ORANGE (410 4210);
FORCEPROP 2 LASTPIN (400 4150) $PN 277
J 0
(410 4160);
DISPLAY 0.617021 (410 4160);
PAINT ORANGE (410 4160);
FORCEPROP 2 LASTPIN (400 4100) $PN 267
J 0
(410 4110);
DISPLAY 0.617021 (410 4110);
PAINT ORANGE (410 4110);
FORCEPROP 2 LASTPIN (400 4050) $PN 266
J 0
(410 4060);
DISPLAY 0.617021 (410 4060);
PAINT ORANGE (410 4060);
FORCEPROP 2 LASTPIN (400 4000) $PN 256
J 0
(410 4010);
DISPLAY 0.617021 (410 4010);
PAINT ORANGE (410 4010);
FORCEPROP 2 LASTPIN (400 3950) $PN 255
J 0
(410 3960);
DISPLAY 0.617021 (410 3960);
PAINT ORANGE (410 3960);
FORCEPROP 2 LASTPIN (400 3900) $PN 245
J 0
(410 3910);
DISPLAY 0.617021 (410 3910);
PAINT ORANGE (410 3910);
FORCEPROP 2 LASTPIN (400 3850) $PN 244
J 0
(410 3860);
DISPLAY 0.617021 (410 3860);
PAINT ORANGE (410 3860);
FORCEPROP 2 LASTPIN (400 3800) $PN 186
J 0
(410 3810);
DISPLAY 0.617021 (410 3810);
PAINT ORANGE (410 3810);
FORCEPROP 2 LASTPIN (400 3750) $PN 185
J 0
(410 3760);
DISPLAY 0.617021 (410 3760);
PAINT ORANGE (410 3760);
FORCEPROP 2 LASTPIN (400 3700) $PN 175
J 0
(410 3710);
DISPLAY 0.617021 (410 3710);
PAINT ORANGE (410 3710);
FORCEPROP 2 LASTPIN (400 3650) $PN 174
J 0
(410 3660);
DISPLAY 0.617021 (410 3660);
PAINT ORANGE (410 3660);
FORCEPROP 2 LASTPIN (400 3600) $PN 164
J 0
(410 3610);
DISPLAY 0.617021 (410 3610);
PAINT ORANGE (410 3610);
FORCEPROP 2 LASTPIN (400 3550) $PN 163
J 0
(410 3560);
DISPLAY 0.617021 (410 3560);
PAINT ORANGE (410 3560);
FORCEPROP 2 LASTPIN (400 3500) $PN 153
J 0
(410 3510);
DISPLAY 0.617021 (410 3510);
PAINT ORANGE (410 3510);
FORCEPROP 2 LASTPIN (400 3450) $PN 152
J 0
(410 3460);
DISPLAY 0.617021 (410 3460);
PAINT ORANGE (410 3460);
FORCEPROP 1 LAST PACK_TYPE PIP
J 0
(-450 5500);
PAINT SKYBLUE (-450 5500);
DISPLAY INVISIBLE (-450 5500);
FORCEPROP 2 LAST BOM_COST MEM
J 0
(-50 4350);
PAINT ORANGE (-50 4350);
DISPLAY INVISIBLE (-50 4350);
FORCEPROP 2 LAST CDS_LIB mstr_sconn
J 0
(-50 4350);
PAINT ORANGE (-50 4350);
DISPLAY INVISIBLE (-50 4350);
FORCEPROP 2 LAST SEC_TYPE PIP
J 0
(-450 5500);
DISPLAY 1.021277 (-450 5500);
PAINT ORANGE (-450 5500);
DISPLAY INVISIBLE (-450 5500);
FORCEPROP 2 LAST SEC 2
J 0
(-450 5500);
DISPLAY 0.680851 (-450 5500);
PAINT MONO (-450 5500);
DISPLAY INVISIBLE (-450 5500);
FORCEPROP 2 LAST CDS_LOCATION J4A1
J 0
(-450 5450);
DISPLAY 0.617021 (-450 5450);
PAINT AQUA (-450 5450);
DISPLAY INVISIBLE (-450 5450);
FORCEPROP 1 LAST PATH I66
J 0
(-50 5400);
PAINT GREEN (-50 5400);
DISPLAY INVISIBLE (-50 5400);
FORCEPROP 2 LAST ROOM DDR4_CH_F
J 0
(-50 4350);
PAINT ORANGE (-50 4350);
DISPLAY INVISIBLE (-50 4350);
FORCEADD TAP..6
R 2
(-1550 3475);
FORCEPROP 3 LASTPIN (-1600 3475) SIG_NAME M_F_DQ<42>
J 0
(-1590 3485);
DISPLAY 0.659574 (-1590 3485);
PAINT MONO (-1590 3485);
DISPLAY INVISIBLE (-1590 3485);
FORCEPROP 1 LASTPIN (-1600 3475) BN 42
J 2
(-1550 3485);
DISPLAY 0.617021 (-1550 3485);
PAINT PINK (-1550 3485);
FORCEPROP 2 LAST CDS_LIB mstr_standard
J 2
(-1550 3475);
DISPLAY 0.787234 (-1550 3475);
PAINT MONO (-1550 3475);
DISPLAY INVISIBLE (-1550 3475);
FORCEPROP 1 LAST BODY_TYPE PLUMBING
J 2
(-1550 3425);
DISPLAY 1.234043 (-1550 3425);
PAINT GREEN (-1550 3425);
DISPLAY INVISIBLE (-1550 3425);
FORCEPROP 1 LAST HDL_TAP TRUE
J 2
(-1875 3350);
DISPLAY 1.234043 (-1875 3350);
PAINT GREEN (-1875 3350);
DISPLAY INVISIBLE (-1875 3350);
FORCEPROP 1 LAST PATH I67
J 2
(-1550 3475);
DISPLAY 0.936170 (-1550 3475);
PAINT GREEN (-1550 3475);
DISPLAY INVISIBLE (-1550 3475);
FORCEADD TAP..6
R 2
(-1550 3425);
FORCEPROP 3 LASTPIN (-1600 3425) SIG_NAME M_F_DQ<43>
J 0
(-1590 3435);
DISPLAY 0.659574 (-1590 3435);
PAINT MONO (-1590 3435);
DISPLAY INVISIBLE (-1590 3435);
FORCEPROP 1 LASTPIN (-1600 3425) BN 43
J 2
(-1550 3435);
DISPLAY 0.617021 (-1550 3435);
PAINT PINK (-1550 3435);
FORCEPROP 2 LAST CDS_LIB mstr_standard
J 2
(-1550 3425);
DISPLAY 0.787234 (-1550 3425);
PAINT MONO (-1550 3425);
DISPLAY INVISIBLE (-1550 3425);
FORCEPROP 1 LAST BODY_TYPE PLUMBING
J 2
(-1550 3375);
DISPLAY 1.234043 (-1550 3375);
PAINT GREEN (-1550 3375);
DISPLAY INVISIBLE (-1550 3375);
FORCEPROP 1 LAST HDL_TAP TRUE
J 2
(-1875 3300);
DISPLAY 1.234043 (-1875 3300);
PAINT GREEN (-1875 3300);
DISPLAY INVISIBLE (-1875 3300);
FORCEPROP 1 LAST PATH I68
J 2
(-1550 3425);
DISPLAY 0.936170 (-1550 3425);
PAINT GREEN (-1550 3425);
DISPLAY INVISIBLE (-1550 3425);
FORCEADD TAP..6
R 2
(-1550 3325);
FORCEPROP 3 LASTPIN (-1600 3325) SIG_NAME M_F_DQ<41>
J 0
(-1590 3335);
DISPLAY 0.659574 (-1590 3335);
PAINT MONO (-1590 3335);
DISPLAY INVISIBLE (-1590 3335);
FORCEPROP 1 LASTPIN (-1600 3325) BN 41
J 2
(-1550 3335);
DISPLAY 0.617021 (-1550 3335);
PAINT PINK (-1550 3335);
FORCEPROP 2 LAST CDS_LIB mstr_standard
J 2
(-1550 3325);
DISPLAY 0.787234 (-1550 3325);
PAINT MONO (-1550 3325);
DISPLAY INVISIBLE (-1550 3325);
FORCEPROP 1 LAST BODY_TYPE PLUMBING
J 2
(-1550 3275);
DISPLAY 1.234043 (-1550 3275);
PAINT GREEN (-1550 3275);
DISPLAY INVISIBLE (-1550 3275);
FORCEPROP 1 LAST HDL_TAP TRUE
J 2
(-1875 3200);
DISPLAY 1.234043 (-1875 3200);
PAINT GREEN (-1875 3200);
DISPLAY INVISIBLE (-1875 3200);
FORCEPROP 1 LAST PATH I69
J 2
(-1550 3325);
DISPLAY 0.936170 (-1550 3325);
PAINT GREEN (-1550 3325);
DISPLAY INVISIBLE (-1550 3325);
FORCEADD TAP..6
R 2
(850 4750);
FORCEPROP 3 LASTPIN (800 4750) SIG_NAME M_F_DQS_DN<13>
J 0
(810 4760);
DISPLAY 0.659574 (810 4760);
PAINT MONO (810 4760);
DISPLAY INVISIBLE (810 4760);
FORCEPROP 1 LASTPIN (800 4750) BN 13
J 2
(850 4760);
DISPLAY 0.617021 (850 4760);
PAINT PINK (850 4760);
FORCEPROP 2 LAST CDS_LIB mstr_standard
J 0
(850 4750);
DISPLAY 0.787234 (850 4750);
PAINT MONO (850 4750);
DISPLAY INVISIBLE (850 4750);
FORCEPROP 1 LAST BODY_TYPE PLUMBING
J 2
(850 4700);
DISPLAY 1.234043 (850 4700);
PAINT GREEN (850 4700);
DISPLAY INVISIBLE (850 4700);
FORCEPROP 1 LAST HDL_TAP TRUE
J 2
(525 4625);
DISPLAY 1.234043 (525 4625);
PAINT GREEN (525 4625);
DISPLAY INVISIBLE (525 4625);
FORCEPROP 1 LAST PATH I7
J 2
(850 4750);
DISPLAY 0.936170 (850 4750);
PAINT GREEN (850 4750);
DISPLAY INVISIBLE (850 4750);
FORCEADD TAP..6
R 2
(-1550 3275);
FORCEPROP 3 LASTPIN (-1600 3275) SIG_NAME M_F_DQ<38>
J 0
(-1590 3285);
DISPLAY 0.659574 (-1590 3285);
PAINT MONO (-1590 3285);
DISPLAY INVISIBLE (-1590 3285);
FORCEPROP 1 LASTPIN (-1600 3275) BN 38
J 2
(-1550 3285);
DISPLAY 0.617021 (-1550 3285);
PAINT PINK (-1550 3285);
FORCEPROP 2 LAST CDS_LIB mstr_standard
J 2
(-1550 3275);
DISPLAY 0.787234 (-1550 3275);
PAINT MONO (-1550 3275);
DISPLAY INVISIBLE (-1550 3275);
FORCEPROP 1 LAST BODY_TYPE PLUMBING
J 2
(-1550 3225);
DISPLAY 1.234043 (-1550 3225);
PAINT GREEN (-1550 3225);
DISPLAY INVISIBLE (-1550 3225);
FORCEPROP 1 LAST HDL_TAP TRUE
J 2
(-1875 3150);
DISPLAY 1.234043 (-1875 3150);
PAINT GREEN (-1875 3150);
DISPLAY INVISIBLE (-1875 3150);
FORCEPROP 1 LAST PATH I70
J 2
(-1550 3275);
DISPLAY 0.936170 (-1550 3275);
PAINT GREEN (-1550 3275);
DISPLAY INVISIBLE (-1550 3275);
FORCEADD TAP..6
R 2
(-1550 3375);
FORCEPROP 3 LASTPIN (-1600 3375) SIG_NAME M_F_DQ<40>
J 0
(-1590 3385);
DISPLAY 0.659574 (-1590 3385);
PAINT MONO (-1590 3385);
DISPLAY INVISIBLE (-1590 3385);
FORCEPROP 1 LASTPIN (-1600 3375) BN 40
J 2
(-1550 3385);
DISPLAY 0.617021 (-1550 3385);
PAINT PINK (-1550 3385);
FORCEPROP 2 LAST CDS_LIB mstr_standard
J 2
(-1550 3375);
DISPLAY 0.787234 (-1550 3375);
PAINT MONO (-1550 3375);
DISPLAY INVISIBLE (-1550 3375);
FORCEPROP 1 LAST BODY_TYPE PLUMBING
J 2
(-1550 3325);
DISPLAY 1.234043 (-1550 3325);
PAINT GREEN (-1550 3325);
DISPLAY INVISIBLE (-1550 3325);
FORCEPROP 1 LAST HDL_TAP TRUE
J 2
(-1875 3250);
DISPLAY 1.234043 (-1875 3250);
PAINT GREEN (-1875 3250);
DISPLAY INVISIBLE (-1875 3250);
FORCEPROP 1 LAST PATH I71
J 2
(-1550 3375);
DISPLAY 0.936170 (-1550 3375);
PAINT GREEN (-1550 3375);
DISPLAY INVISIBLE (-1550 3375);
FORCEADD TAP..6
R 2
(-1550 3225);
FORCEPROP 3 LASTPIN (-1600 3225) SIG_NAME M_F_DQ<39>
J 0
(-1590 3235);
DISPLAY 0.659574 (-1590 3235);
PAINT MONO (-1590 3235);
DISPLAY INVISIBLE (-1590 3235);
FORCEPROP 1 LASTPIN (-1600 3225) BN 39
J 2
(-1550 3235);
DISPLAY 0.617021 (-1550 3235);
PAINT PINK (-1550 3235);
FORCEPROP 2 LAST CDS_LIB mstr_standard
J 2
(-1550 3225);
DISPLAY 0.787234 (-1550 3225);
PAINT MONO (-1550 3225);
DISPLAY INVISIBLE (-1550 3225);
FORCEPROP 1 LAST BODY_TYPE PLUMBING
J 2
(-1550 3175);
DISPLAY 1.234043 (-1550 3175);
PAINT GREEN (-1550 3175);
DISPLAY INVISIBLE (-1550 3175);
FORCEPROP 1 LAST HDL_TAP TRUE
J 2
(-1875 3100);
DISPLAY 1.234043 (-1875 3100);
PAINT GREEN (-1875 3100);
DISPLAY INVISIBLE (-1875 3100);
FORCEPROP 1 LAST PATH I72
J 2
(-1550 3225);
DISPLAY 0.936170 (-1550 3225);
PAINT GREEN (-1550 3225);
DISPLAY INVISIBLE (-1550 3225);
FORCEADD TAP..6
R 2
(-1550 3175);
FORCEPROP 3 LASTPIN (-1600 3175) SIG_NAME M_F_DQ<36>
J 0
(-1590 3185);
DISPLAY 0.659574 (-1590 3185);
PAINT MONO (-1590 3185);
DISPLAY INVISIBLE (-1590 3185);
FORCEPROP 1 LASTPIN (-1600 3175) BN 36
J 2
(-1550 3185);
DISPLAY 0.617021 (-1550 3185);
PAINT PINK (-1550 3185);
FORCEPROP 2 LAST CDS_LIB mstr_standard
J 2
(-1550 3175);
DISPLAY 0.787234 (-1550 3175);
PAINT MONO (-1550 3175);
DISPLAY INVISIBLE (-1550 3175);
FORCEPROP 1 LAST BODY_TYPE PLUMBING
J 2
(-1550 3125);
DISPLAY 1.234043 (-1550 3125);
PAINT GREEN (-1550 3125);
DISPLAY INVISIBLE (-1550 3125);
FORCEPROP 1 LAST HDL_TAP TRUE
J 2
(-1875 3050);
DISPLAY 1.234043 (-1875 3050);
PAINT GREEN (-1875 3050);
DISPLAY INVISIBLE (-1875 3050);
FORCEPROP 1 LAST PATH I73
J 2
(-1550 3175);
DISPLAY 0.936170 (-1550 3175);
PAINT GREEN (-1550 3175);
DISPLAY INVISIBLE (-1550 3175);
FORCEADD TAP..6
R 2
(-1550 3125);
FORCEPROP 3 LASTPIN (-1600 3125) SIG_NAME M_F_DQ<37>
J 0
(-1590 3135);
DISPLAY 0.659574 (-1590 3135);
PAINT MONO (-1590 3135);
DISPLAY INVISIBLE (-1590 3135);
FORCEPROP 1 LASTPIN (-1600 3125) BN 37
J 2
(-1550 3135);
DISPLAY 0.617021 (-1550 3135);
PAINT PINK (-1550 3135);
FORCEPROP 2 LAST CDS_LIB mstr_standard
J 2
(-1550 3125);
DISPLAY 0.787234 (-1550 3125);
PAINT MONO (-1550 3125);
DISPLAY INVISIBLE (-1550 3125);
FORCEPROP 1 LAST BODY_TYPE PLUMBING
J 2
(-1550 3075);
DISPLAY 1.234043 (-1550 3075);
PAINT GREEN (-1550 3075);
DISPLAY INVISIBLE (-1550 3075);
FORCEPROP 1 LAST HDL_TAP TRUE
J 2
(-1875 3000);
DISPLAY 1.234043 (-1875 3000);
PAINT GREEN (-1875 3000);
DISPLAY INVISIBLE (-1875 3000);
FORCEPROP 1 LAST PATH I74
J 2
(-1550 3125);
DISPLAY 0.936170 (-1550 3125);
PAINT GREEN (-1550 3125);
DISPLAY INVISIBLE (-1550 3125);
FORCEADD TAP..6
R 2
(-1550 3025);
FORCEPROP 3 LASTPIN (-1600 3025) SIG_NAME M_F_DQ<35>
J 0
(-1590 3035);
DISPLAY 0.659574 (-1590 3035);
PAINT MONO (-1590 3035);
DISPLAY INVISIBLE (-1590 3035);
FORCEPROP 1 LASTPIN (-1600 3025) BN 35
J 2
(-1550 3035);
DISPLAY 0.617021 (-1550 3035);
PAINT PINK (-1550 3035);
FORCEPROP 2 LAST CDS_LIB mstr_standard
J 2
(-1550 3025);
DISPLAY 0.787234 (-1550 3025);
PAINT MONO (-1550 3025);
DISPLAY INVISIBLE (-1550 3025);
FORCEPROP 1 LAST BODY_TYPE PLUMBING
J 2
(-1550 2975);
DISPLAY 1.234043 (-1550 2975);
PAINT GREEN (-1550 2975);
DISPLAY INVISIBLE (-1550 2975);
FORCEPROP 1 LAST HDL_TAP TRUE
J 2
(-1875 2900);
DISPLAY 1.234043 (-1875 2900);
PAINT GREEN (-1875 2900);
DISPLAY INVISIBLE (-1875 2900);
FORCEPROP 1 LAST PATH I75
J 2
(-1550 3025);
DISPLAY 0.936170 (-1550 3025);
PAINT GREEN (-1550 3025);
DISPLAY INVISIBLE (-1550 3025);
FORCEADD TAP..6
R 2
(-1550 3075);
FORCEPROP 3 LASTPIN (-1600 3075) SIG_NAME M_F_DQ<34>
J 0
(-1590 3085);
DISPLAY 0.659574 (-1590 3085);
PAINT MONO (-1590 3085);
DISPLAY INVISIBLE (-1590 3085);
FORCEPROP 1 LASTPIN (-1600 3075) BN 34
J 2
(-1550 3085);
DISPLAY 0.617021 (-1550 3085);
PAINT PINK (-1550 3085);
FORCEPROP 2 LAST CDS_LIB mstr_standard
J 2
(-1550 3075);
DISPLAY 0.787234 (-1550 3075);
PAINT MONO (-1550 3075);
DISPLAY INVISIBLE (-1550 3075);
FORCEPROP 1 LAST BODY_TYPE PLUMBING
J 2
(-1550 3025);
DISPLAY 1.234043 (-1550 3025);
PAINT GREEN (-1550 3025);
DISPLAY INVISIBLE (-1550 3025);
FORCEPROP 1 LAST HDL_TAP TRUE
J 2
(-1875 2950);
DISPLAY 1.234043 (-1875 2950);
PAINT GREEN (-1875 2950);
DISPLAY INVISIBLE (-1875 2950);
FORCEPROP 1 LAST PATH I76
J 2
(-1550 3075);
DISPLAY 0.936170 (-1550 3075);
PAINT GREEN (-1550 3075);
DISPLAY INVISIBLE (-1550 3075);
FORCEADD TAP..6
R 2
(-1550 2975);
FORCEPROP 3 LASTPIN (-1600 2975) SIG_NAME M_F_DQ<32>
J 0
(-1590 2985);
DISPLAY 0.659574 (-1590 2985);
PAINT MONO (-1590 2985);
DISPLAY INVISIBLE (-1590 2985);
FORCEPROP 1 LASTPIN (-1600 2975) BN 32
J 2
(-1550 2985);
DISPLAY 0.617021 (-1550 2985);
PAINT PINK (-1550 2985);
FORCEPROP 2 LAST CDS_LIB mstr_standard
J 2
(-1550 2975);
DISPLAY 0.787234 (-1550 2975);
PAINT MONO (-1550 2975);
DISPLAY INVISIBLE (-1550 2975);
FORCEPROP 1 LAST BODY_TYPE PLUMBING
J 2
(-1550 2925);
DISPLAY 1.234043 (-1550 2925);
PAINT GREEN (-1550 2925);
DISPLAY INVISIBLE (-1550 2925);
FORCEPROP 1 LAST HDL_TAP TRUE
J 2
(-1875 2850);
DISPLAY 1.234043 (-1875 2850);
PAINT GREEN (-1875 2850);
DISPLAY INVISIBLE (-1875 2850);
FORCEPROP 1 LAST PATH I77
J 2
(-1550 2975);
DISPLAY 0.936170 (-1550 2975);
PAINT GREEN (-1550 2975);
DISPLAY INVISIBLE (-1550 2975);
FORCEADD TAP..6
R 2
(-1550 2925);
FORCEPROP 3 LASTPIN (-1600 2925) SIG_NAME M_F_DQ<33>
J 0
(-1590 2935);
DISPLAY 0.659574 (-1590 2935);
PAINT MONO (-1590 2935);
DISPLAY INVISIBLE (-1590 2935);
FORCEPROP 1 LASTPIN (-1600 2925) BN 33
J 2
(-1550 2935);
DISPLAY 0.617021 (-1550 2935);
PAINT PINK (-1550 2935);
FORCEPROP 2 LAST CDS_LIB mstr_standard
J 2
(-1550 2925);
DISPLAY 0.787234 (-1550 2925);
PAINT MONO (-1550 2925);
DISPLAY INVISIBLE (-1550 2925);
FORCEPROP 1 LAST BODY_TYPE PLUMBING
J 2
(-1550 2875);
DISPLAY 1.234043 (-1550 2875);
PAINT GREEN (-1550 2875);
DISPLAY INVISIBLE (-1550 2875);
FORCEPROP 1 LAST HDL_TAP TRUE
J 2
(-1875 2800);
DISPLAY 1.234043 (-1875 2800);
PAINT GREEN (-1875 2800);
DISPLAY INVISIBLE (-1875 2800);
FORCEPROP 1 LAST PATH I78
J 2
(-1550 2925);
DISPLAY 0.936170 (-1550 2925);
PAINT GREEN (-1550 2925);
DISPLAY INVISIBLE (-1550 2925);
FORCEADD TAP..6
R 2
(-1550 2775);
FORCEPROP 3 LASTPIN (-1600 2775) SIG_NAME M_F_DQ<28>
J 0
(-1590 2785);
DISPLAY 0.659574 (-1590 2785);
PAINT MONO (-1590 2785);
DISPLAY INVISIBLE (-1590 2785);
FORCEPROP 1 LASTPIN (-1600 2775) BN 28
J 2
(-1550 2785);
DISPLAY 0.617021 (-1550 2785);
PAINT PINK (-1550 2785);
FORCEPROP 2 LAST CDS_LIB mstr_standard
J 2
(-1550 2775);
DISPLAY 0.787234 (-1550 2775);
PAINT MONO (-1550 2775);
DISPLAY INVISIBLE (-1550 2775);
FORCEPROP 1 LAST BODY_TYPE PLUMBING
J 2
(-1550 2725);
DISPLAY 1.234043 (-1550 2725);
PAINT GREEN (-1550 2725);
DISPLAY INVISIBLE (-1550 2725);
FORCEPROP 1 LAST HDL_TAP TRUE
J 2
(-1875 2650);
DISPLAY 1.234043 (-1875 2650);
PAINT GREEN (-1875 2650);
DISPLAY INVISIBLE (-1875 2650);
FORCEPROP 1 LAST PATH I79
J 2
(-1550 2775);
DISPLAY 0.936170 (-1550 2775);
PAINT GREEN (-1550 2775);
DISPLAY INVISIBLE (-1550 2775);
FORCEADD TAP..6
R 2
(850 4850);
FORCEPROP 3 LASTPIN (800 4850) SIG_NAME M_F_DQS_DN<14>
J 0
(810 4860);
DISPLAY 0.659574 (810 4860);
PAINT MONO (810 4860);
DISPLAY INVISIBLE (810 4860);
FORCEPROP 1 LASTPIN (800 4850) BN 14
J 2
(850 4860);
DISPLAY 0.617021 (850 4860);
PAINT PINK (850 4860);
FORCEPROP 2 LAST CDS_LIB mstr_standard
J 0
(850 4850);
DISPLAY 0.787234 (850 4850);
PAINT MONO (850 4850);
DISPLAY INVISIBLE (850 4850);
FORCEPROP 1 LAST BODY_TYPE PLUMBING
J 2
(850 4800);
DISPLAY 1.234043 (850 4800);
PAINT GREEN (850 4800);
DISPLAY INVISIBLE (850 4800);
FORCEPROP 1 LAST HDL_TAP TRUE
J 2
(525 4725);
DISPLAY 1.234043 (525 4725);
PAINT GREEN (525 4725);
DISPLAY INVISIBLE (525 4725);
FORCEPROP 1 LAST PATH I8
J 2
(850 4850);
DISPLAY 0.936170 (850 4850);
PAINT GREEN (850 4850);
DISPLAY INVISIBLE (850 4850);
FORCEADD TAP..6
R 2
(-1550 2875);
FORCEPROP 3 LASTPIN (-1600 2875) SIG_NAME M_F_DQ<30>
J 0
(-1590 2885);
DISPLAY 0.659574 (-1590 2885);
PAINT MONO (-1590 2885);
DISPLAY INVISIBLE (-1590 2885);
FORCEPROP 1 LASTPIN (-1600 2875) BN 30
J 2
(-1550 2885);
DISPLAY 0.617021 (-1550 2885);
PAINT PINK (-1550 2885);
FORCEPROP 2 LAST CDS_LIB mstr_standard
J 2
(-1550 2875);
DISPLAY 0.787234 (-1550 2875);
PAINT MONO (-1550 2875);
DISPLAY INVISIBLE (-1550 2875);
FORCEPROP 1 LAST BODY_TYPE PLUMBING
J 2
(-1550 2825);
DISPLAY 1.234043 (-1550 2825);
PAINT GREEN (-1550 2825);
DISPLAY INVISIBLE (-1550 2825);
FORCEPROP 1 LAST HDL_TAP TRUE
J 2
(-1875 2750);
DISPLAY 1.234043 (-1875 2750);
PAINT GREEN (-1875 2750);
DISPLAY INVISIBLE (-1875 2750);
FORCEPROP 1 LAST PATH I80
J 2
(-1550 2875);
DISPLAY 0.936170 (-1550 2875);
PAINT GREEN (-1550 2875);
DISPLAY INVISIBLE (-1550 2875);
FORCEADD TAP..6
R 2
(-1550 2825);
FORCEPROP 3 LASTPIN (-1600 2825) SIG_NAME M_F_DQ<31>
J 0
(-1590 2835);
DISPLAY 0.659574 (-1590 2835);
PAINT MONO (-1590 2835);
DISPLAY INVISIBLE (-1590 2835);
FORCEPROP 1 LASTPIN (-1600 2825) BN 31
J 2
(-1550 2835);
DISPLAY 0.617021 (-1550 2835);
PAINT PINK (-1550 2835);
FORCEPROP 2 LAST CDS_LIB mstr_standard
J 2
(-1550 2825);
DISPLAY 0.787234 (-1550 2825);
PAINT MONO (-1550 2825);
DISPLAY INVISIBLE (-1550 2825);
FORCEPROP 1 LAST BODY_TYPE PLUMBING
J 2
(-1550 2775);
DISPLAY 1.234043 (-1550 2775);
PAINT GREEN (-1550 2775);
DISPLAY INVISIBLE (-1550 2775);
FORCEPROP 1 LAST HDL_TAP TRUE
J 2
(-1875 2700);
DISPLAY 1.234043 (-1875 2700);
PAINT GREEN (-1875 2700);
DISPLAY INVISIBLE (-1875 2700);
FORCEPROP 1 LAST PATH I81
J 2
(-1550 2825);
DISPLAY 0.936170 (-1550 2825);
PAINT GREEN (-1550 2825);
DISPLAY INVISIBLE (-1550 2825);
FORCEADD TAP..6
R 2
(-1550 2675);
FORCEPROP 3 LASTPIN (-1600 2675) SIG_NAME M_F_DQ<26>
J 0
(-1590 2685);
DISPLAY 0.659574 (-1590 2685);
PAINT MONO (-1590 2685);
DISPLAY INVISIBLE (-1590 2685);
FORCEPROP 1 LASTPIN (-1600 2675) BN 26
J 2
(-1550 2685);
DISPLAY 0.617021 (-1550 2685);
PAINT PINK (-1550 2685);
FORCEPROP 2 LAST CDS_LIB mstr_standard
J 2
(-1550 2675);
DISPLAY 0.787234 (-1550 2675);
PAINT MONO (-1550 2675);
DISPLAY INVISIBLE (-1550 2675);
FORCEPROP 1 LAST BODY_TYPE PLUMBING
J 2
(-1550 2625);
DISPLAY 1.234043 (-1550 2625);
PAINT GREEN (-1550 2625);
DISPLAY INVISIBLE (-1550 2625);
FORCEPROP 1 LAST HDL_TAP TRUE
J 2
(-1875 2550);
DISPLAY 1.234043 (-1875 2550);
PAINT GREEN (-1875 2550);
DISPLAY INVISIBLE (-1875 2550);
FORCEPROP 1 LAST PATH I82
J 2
(-1550 2675);
DISPLAY 0.936170 (-1550 2675);
PAINT GREEN (-1550 2675);
DISPLAY INVISIBLE (-1550 2675);
FORCEADD TAP..6
R 2
(-1550 2725);
FORCEPROP 3 LASTPIN (-1600 2725) SIG_NAME M_F_DQ<29>
J 0
(-1590 2735);
DISPLAY 0.659574 (-1590 2735);
PAINT MONO (-1590 2735);
DISPLAY INVISIBLE (-1590 2735);
FORCEPROP 1 LASTPIN (-1600 2725) BN 29
J 2
(-1550 2735);
DISPLAY 0.617021 (-1550 2735);
PAINT PINK (-1550 2735);
FORCEPROP 2 LAST CDS_LIB mstr_standard
J 2
(-1550 2725);
DISPLAY 0.787234 (-1550 2725);
PAINT MONO (-1550 2725);
DISPLAY INVISIBLE (-1550 2725);
FORCEPROP 1 LAST BODY_TYPE PLUMBING
J 2
(-1550 2675);
DISPLAY 1.234043 (-1550 2675);
PAINT GREEN (-1550 2675);
DISPLAY INVISIBLE (-1550 2675);
FORCEPROP 1 LAST HDL_TAP TRUE
J 2
(-1875 2600);
DISPLAY 1.234043 (-1875 2600);
PAINT GREEN (-1875 2600);
DISPLAY INVISIBLE (-1875 2600);
FORCEPROP 1 LAST PATH I83
J 2
(-1550 2725);
DISPLAY 0.936170 (-1550 2725);
PAINT GREEN (-1550 2725);
DISPLAY INVISIBLE (-1550 2725);
FORCEADD TAP..6
R 2
(-1550 2625);
FORCEPROP 3 LASTPIN (-1600 2625) SIG_NAME M_F_DQ<27>
J 0
(-1590 2635);
DISPLAY 0.659574 (-1590 2635);
PAINT MONO (-1590 2635);
DISPLAY INVISIBLE (-1590 2635);
FORCEPROP 1 LASTPIN (-1600 2625) BN 27
J 2
(-1550 2635);
DISPLAY 0.617021 (-1550 2635);
PAINT PINK (-1550 2635);
FORCEPROP 2 LAST CDS_LIB mstr_standard
J 2
(-1550 2625);
DISPLAY 0.787234 (-1550 2625);
PAINT MONO (-1550 2625);
DISPLAY INVISIBLE (-1550 2625);
FORCEPROP 1 LAST BODY_TYPE PLUMBING
J 2
(-1550 2575);
DISPLAY 1.234043 (-1550 2575);
PAINT GREEN (-1550 2575);
DISPLAY INVISIBLE (-1550 2575);
FORCEPROP 1 LAST HDL_TAP TRUE
J 2
(-1875 2500);
DISPLAY 1.234043 (-1875 2500);
PAINT GREEN (-1875 2500);
DISPLAY INVISIBLE (-1875 2500);
FORCEPROP 1 LAST PATH I84
J 2
(-1550 2625);
DISPLAY 0.936170 (-1550 2625);
PAINT GREEN (-1550 2625);
DISPLAY INVISIBLE (-1550 2625);
FORCEADD TAP..6
R 2
(-1550 2525);
FORCEPROP 3 LASTPIN (-1600 2525) SIG_NAME M_F_DQ<25>
J 0
(-1590 2535);
DISPLAY 0.659574 (-1590 2535);
PAINT MONO (-1590 2535);
DISPLAY INVISIBLE (-1590 2535);
FORCEPROP 1 LASTPIN (-1600 2525) BN 25
J 2
(-1550 2535);
DISPLAY 0.617021 (-1550 2535);
PAINT PINK (-1550 2535);
FORCEPROP 2 LAST CDS_LIB mstr_standard
J 2
(-1550 2525);
DISPLAY 0.787234 (-1550 2525);
PAINT MONO (-1550 2525);
DISPLAY INVISIBLE (-1550 2525);
FORCEPROP 1 LAST BODY_TYPE PLUMBING
J 2
(-1550 2475);
DISPLAY 1.234043 (-1550 2475);
PAINT GREEN (-1550 2475);
DISPLAY INVISIBLE (-1550 2475);
FORCEPROP 1 LAST HDL_TAP TRUE
J 2
(-1875 2400);
DISPLAY 1.234043 (-1875 2400);
PAINT GREEN (-1875 2400);
DISPLAY INVISIBLE (-1875 2400);
FORCEPROP 1 LAST PATH I85
J 2
(-1550 2525);
DISPLAY 0.936170 (-1550 2525);
PAINT GREEN (-1550 2525);
DISPLAY INVISIBLE (-1550 2525);
FORCEADD TAP..6
R 2
(-1550 2575);
FORCEPROP 3 LASTPIN (-1600 2575) SIG_NAME M_F_DQ<24>
J 0
(-1590 2585);
DISPLAY 0.659574 (-1590 2585);
PAINT MONO (-1590 2585);
DISPLAY INVISIBLE (-1590 2585);
FORCEPROP 1 LASTPIN (-1600 2575) BN 24
J 2
(-1550 2585);
DISPLAY 0.617021 (-1550 2585);
PAINT PINK (-1550 2585);
FORCEPROP 2 LAST CDS_LIB mstr_standard
J 2
(-1550 2575);
DISPLAY 0.787234 (-1550 2575);
PAINT MONO (-1550 2575);
DISPLAY INVISIBLE (-1550 2575);
FORCEPROP 1 LAST BODY_TYPE PLUMBING
J 2
(-1550 2525);
DISPLAY 1.234043 (-1550 2525);
PAINT GREEN (-1550 2525);
DISPLAY INVISIBLE (-1550 2525);
FORCEPROP 1 LAST HDL_TAP TRUE
J 2
(-1875 2450);
DISPLAY 1.234043 (-1875 2450);
PAINT GREEN (-1875 2450);
DISPLAY INVISIBLE (-1875 2450);
FORCEPROP 1 LAST PATH I86
J 2
(-1550 2575);
DISPLAY 0.936170 (-1550 2575);
PAINT GREEN (-1550 2575);
DISPLAY INVISIBLE (-1550 2575);
FORCEADD TAP..6
R 2
(-1550 2425);
FORCEPROP 3 LASTPIN (-1600 2425) SIG_NAME M_F_DQ<23>
J 0
(-1590 2435);
DISPLAY 0.659574 (-1590 2435);
PAINT MONO (-1590 2435);
DISPLAY INVISIBLE (-1590 2435);
FORCEPROP 1 LASTPIN (-1600 2425) BN 23
J 2
(-1550 2435);
DISPLAY 0.617021 (-1550 2435);
PAINT PINK (-1550 2435);
FORCEPROP 2 LAST CDS_LIB mstr_standard
J 2
(-1550 2425);
DISPLAY 0.787234 (-1550 2425);
PAINT MONO (-1550 2425);
DISPLAY INVISIBLE (-1550 2425);
FORCEPROP 1 LAST BODY_TYPE PLUMBING
J 2
(-1550 2375);
DISPLAY 1.234043 (-1550 2375);
PAINT GREEN (-1550 2375);
DISPLAY INVISIBLE (-1550 2375);
FORCEPROP 1 LAST HDL_TAP TRUE
J 2
(-1875 2300);
DISPLAY 1.234043 (-1875 2300);
PAINT GREEN (-1875 2300);
DISPLAY INVISIBLE (-1875 2300);
FORCEPROP 1 LAST PATH I87
J 2
(-1550 2425);
DISPLAY 0.936170 (-1550 2425);
PAINT GREEN (-1550 2425);
DISPLAY INVISIBLE (-1550 2425);
FORCEADD TAP..6
R 2
(-1550 2475);
FORCEPROP 3 LASTPIN (-1600 2475) SIG_NAME M_F_DQ<22>
J 0
(-1590 2485);
DISPLAY 0.659574 (-1590 2485);
PAINT MONO (-1590 2485);
DISPLAY INVISIBLE (-1590 2485);
FORCEPROP 1 LASTPIN (-1600 2475) BN 22
J 2
(-1550 2485);
DISPLAY 0.617021 (-1550 2485);
PAINT PINK (-1550 2485);
FORCEPROP 2 LAST CDS_LIB mstr_standard
J 2
(-1550 2475);
DISPLAY 0.787234 (-1550 2475);
PAINT MONO (-1550 2475);
DISPLAY INVISIBLE (-1550 2475);
FORCEPROP 1 LAST BODY_TYPE PLUMBING
J 2
(-1550 2425);
DISPLAY 1.234043 (-1550 2425);
PAINT GREEN (-1550 2425);
DISPLAY INVISIBLE (-1550 2425);
FORCEPROP 1 LAST HDL_TAP TRUE
J 2
(-1875 2350);
DISPLAY 1.234043 (-1875 2350);
PAINT GREEN (-1875 2350);
DISPLAY INVISIBLE (-1875 2350);
FORCEPROP 1 LAST PATH I88
J 2
(-1550 2475);
DISPLAY 0.936170 (-1550 2475);
PAINT GREEN (-1550 2475);
DISPLAY INVISIBLE (-1550 2475);
FORCEADD TAP..6
R 2
(-1550 2375);
FORCEPROP 3 LASTPIN (-1600 2375) SIG_NAME M_F_DQ<20>
J 0
(-1590 2385);
DISPLAY 0.659574 (-1590 2385);
PAINT MONO (-1590 2385);
DISPLAY INVISIBLE (-1590 2385);
FORCEPROP 1 LASTPIN (-1600 2375) BN 20
J 2
(-1550 2385);
DISPLAY 0.617021 (-1550 2385);
PAINT PINK (-1550 2385);
FORCEPROP 2 LAST CDS_LIB mstr_standard
J 2
(-1550 2375);
DISPLAY 0.787234 (-1550 2375);
PAINT MONO (-1550 2375);
DISPLAY INVISIBLE (-1550 2375);
FORCEPROP 1 LAST BODY_TYPE PLUMBING
J 2
(-1550 2325);
DISPLAY 1.234043 (-1550 2325);
PAINT GREEN (-1550 2325);
DISPLAY INVISIBLE (-1550 2325);
FORCEPROP 1 LAST HDL_TAP TRUE
J 2
(-1875 2250);
DISPLAY 1.234043 (-1875 2250);
PAINT GREEN (-1875 2250);
DISPLAY INVISIBLE (-1875 2250);
FORCEPROP 1 LAST PATH I89
J 2
(-1550 2375);
DISPLAY 0.936170 (-1550 2375);
PAINT GREEN (-1550 2375);
DISPLAY INVISIBLE (-1550 2375);
FORCEADD TAP..6
R 2
(850 4650);
FORCEPROP 3 LASTPIN (800 4650) SIG_NAME M_F_DQS_DN<12>
J 0
(810 4660);
DISPLAY 0.659574 (810 4660);
PAINT MONO (810 4660);
DISPLAY INVISIBLE (810 4660);
FORCEPROP 1 LASTPIN (800 4650) BN 12
J 2
(850 4660);
DISPLAY 0.617021 (850 4660);
PAINT PINK (850 4660);
FORCEPROP 2 LAST CDS_LIB mstr_standard
J 0
(850 4650);
DISPLAY 0.787234 (850 4650);
PAINT MONO (850 4650);
DISPLAY INVISIBLE (850 4650);
FORCEPROP 1 LAST BODY_TYPE PLUMBING
J 2
(850 4600);
DISPLAY 1.234043 (850 4600);
PAINT GREEN (850 4600);
DISPLAY INVISIBLE (850 4600);
FORCEPROP 1 LAST HDL_TAP TRUE
J 2
(525 4525);
DISPLAY 1.234043 (525 4525);
PAINT GREEN (525 4525);
DISPLAY INVISIBLE (525 4525);
FORCEPROP 1 LAST PATH I9
J 2
(850 4650);
DISPLAY 0.936170 (850 4650);
PAINT GREEN (850 4650);
DISPLAY INVISIBLE (850 4650);
FORCEADD TAP..6
R 2
(-1550 2325);
FORCEPROP 3 LASTPIN (-1600 2325) SIG_NAME M_F_DQ<21>
J 0
(-1590 2335);
DISPLAY 0.659574 (-1590 2335);
PAINT MONO (-1590 2335);
DISPLAY INVISIBLE (-1590 2335);
FORCEPROP 1 LASTPIN (-1600 2325) BN 21
J 2
(-1550 2335);
DISPLAY 0.617021 (-1550 2335);
PAINT PINK (-1550 2335);
FORCEPROP 2 LAST CDS_LIB mstr_standard
J 2
(-1550 2325);
DISPLAY 0.787234 (-1550 2325);
PAINT MONO (-1550 2325);
DISPLAY INVISIBLE (-1550 2325);
FORCEPROP 1 LAST BODY_TYPE PLUMBING
J 2
(-1550 2275);
DISPLAY 1.234043 (-1550 2275);
PAINT GREEN (-1550 2275);
DISPLAY INVISIBLE (-1550 2275);
FORCEPROP 1 LAST HDL_TAP TRUE
J 2
(-1875 2200);
DISPLAY 1.234043 (-1875 2200);
PAINT GREEN (-1875 2200);
DISPLAY INVISIBLE (-1875 2200);
FORCEPROP 1 LAST PATH I90
J 2
(-1550 2325);
DISPLAY 0.936170 (-1550 2325);
PAINT GREEN (-1550 2325);
DISPLAY INVISIBLE (-1550 2325);
FORCEADD TAP..6
R 2
(-1550 2275);
FORCEPROP 3 LASTPIN (-1600 2275) SIG_NAME M_F_DQ<18>
J 0
(-1590 2285);
DISPLAY 0.659574 (-1590 2285);
PAINT MONO (-1590 2285);
DISPLAY INVISIBLE (-1590 2285);
FORCEPROP 1 LASTPIN (-1600 2275) BN 18
J 2
(-1550 2285);
DISPLAY 0.617021 (-1550 2285);
PAINT PINK (-1550 2285);
FORCEPROP 2 LAST CDS_LIB mstr_standard
J 2
(-1550 2275);
DISPLAY 0.787234 (-1550 2275);
PAINT MONO (-1550 2275);
DISPLAY INVISIBLE (-1550 2275);
FORCEPROP 1 LAST BODY_TYPE PLUMBING
J 2
(-1550 2225);
DISPLAY 1.234043 (-1550 2225);
PAINT GREEN (-1550 2225);
DISPLAY INVISIBLE (-1550 2225);
FORCEPROP 1 LAST HDL_TAP TRUE
J 2
(-1875 2150);
DISPLAY 1.234043 (-1875 2150);
PAINT GREEN (-1875 2150);
DISPLAY INVISIBLE (-1875 2150);
FORCEPROP 1 LAST PATH I91
J 2
(-1550 2275);
DISPLAY 0.936170 (-1550 2275);
PAINT GREEN (-1550 2275);
DISPLAY INVISIBLE (-1550 2275);
FORCEADD TAP..6
R 2
(-1550 2225);
FORCEPROP 3 LASTPIN (-1600 2225) SIG_NAME M_F_DQ<19>
J 0
(-1590 2235);
DISPLAY 0.659574 (-1590 2235);
PAINT MONO (-1590 2235);
DISPLAY INVISIBLE (-1590 2235);
FORCEPROP 1 LASTPIN (-1600 2225) BN 19
J 2
(-1550 2235);
DISPLAY 0.617021 (-1550 2235);
PAINT PINK (-1550 2235);
FORCEPROP 2 LAST CDS_LIB mstr_standard
J 2
(-1550 2225);
DISPLAY 0.787234 (-1550 2225);
PAINT MONO (-1550 2225);
DISPLAY INVISIBLE (-1550 2225);
FORCEPROP 1 LAST BODY_TYPE PLUMBING
J 2
(-1550 2175);
DISPLAY 1.234043 (-1550 2175);
PAINT GREEN (-1550 2175);
DISPLAY INVISIBLE (-1550 2175);
FORCEPROP 1 LAST HDL_TAP TRUE
J 2
(-1875 2100);
DISPLAY 1.234043 (-1875 2100);
PAINT GREEN (-1875 2100);
DISPLAY INVISIBLE (-1875 2100);
FORCEPROP 1 LAST PATH I92
J 2
(-1550 2225);
DISPLAY 0.936170 (-1550 2225);
PAINT GREEN (-1550 2225);
DISPLAY INVISIBLE (-1550 2225);
FORCEADD TAP..6
R 2
(-1550 2125);
FORCEPROP 3 LASTPIN (-1600 2125) SIG_NAME M_F_DQ<17>
J 0
(-1590 2135);
DISPLAY 0.659574 (-1590 2135);
PAINT MONO (-1590 2135);
DISPLAY INVISIBLE (-1590 2135);
FORCEPROP 1 LASTPIN (-1600 2125) BN 17
J 2
(-1550 2135);
DISPLAY 0.617021 (-1550 2135);
PAINT PINK (-1550 2135);
FORCEPROP 2 LAST CDS_LIB mstr_standard
J 2
(-1550 2125);
DISPLAY 0.787234 (-1550 2125);
PAINT MONO (-1550 2125);
DISPLAY INVISIBLE (-1550 2125);
FORCEPROP 1 LAST BODY_TYPE PLUMBING
J 2
(-1550 2075);
DISPLAY 1.234043 (-1550 2075);
PAINT GREEN (-1550 2075);
DISPLAY INVISIBLE (-1550 2075);
FORCEPROP 1 LAST HDL_TAP TRUE
J 2
(-1875 2000);
DISPLAY 1.234043 (-1875 2000);
PAINT GREEN (-1875 2000);
DISPLAY INVISIBLE (-1875 2000);
FORCEPROP 1 LAST PATH I93
J 2
(-1550 2125);
DISPLAY 0.936170 (-1550 2125);
PAINT GREEN (-1550 2125);
DISPLAY INVISIBLE (-1550 2125);
FORCEADD TAP..6
R 2
(-1550 2175);
FORCEPROP 3 LASTPIN (-1600 2175) SIG_NAME M_F_DQ<16>
J 0
(-1590 2185);
DISPLAY 0.659574 (-1590 2185);
PAINT MONO (-1590 2185);
DISPLAY INVISIBLE (-1590 2185);
FORCEPROP 1 LASTPIN (-1600 2175) BN 16
J 2
(-1550 2185);
DISPLAY 0.617021 (-1550 2185);
PAINT PINK (-1550 2185);
FORCEPROP 2 LAST CDS_LIB mstr_standard
J 2
(-1550 2175);
DISPLAY 0.787234 (-1550 2175);
PAINT MONO (-1550 2175);
DISPLAY INVISIBLE (-1550 2175);
FORCEPROP 1 LAST BODY_TYPE PLUMBING
J 2
(-1550 2125);
DISPLAY 1.234043 (-1550 2125);
PAINT GREEN (-1550 2125);
DISPLAY INVISIBLE (-1550 2125);
FORCEPROP 1 LAST HDL_TAP TRUE
J 2
(-1875 2050);
DISPLAY 1.234043 (-1875 2050);
PAINT GREEN (-1875 2050);
DISPLAY INVISIBLE (-1875 2050);
FORCEPROP 1 LAST PATH I94
J 2
(-1550 2175);
DISPLAY 0.936170 (-1550 2175);
PAINT GREEN (-1550 2175);
DISPLAY INVISIBLE (-1550 2175);
FORCEADD TAP..6
R 2
(-1550 2075);
FORCEPROP 3 LASTPIN (-1600 2075) SIG_NAME M_F_DQ<14>
J 0
(-1590 2085);
DISPLAY 0.659574 (-1590 2085);
PAINT MONO (-1590 2085);
DISPLAY INVISIBLE (-1590 2085);
FORCEPROP 1 LASTPIN (-1600 2075) BN 14
J 2
(-1550 2085);
DISPLAY 0.617021 (-1550 2085);
PAINT PINK (-1550 2085);
FORCEPROP 2 LAST CDS_LIB mstr_standard
J 2
(-1550 2075);
DISPLAY 0.787234 (-1550 2075);
PAINT MONO (-1550 2075);
DISPLAY INVISIBLE (-1550 2075);
FORCEPROP 1 LAST BODY_TYPE PLUMBING
J 2
(-1550 2025);
DISPLAY 1.234043 (-1550 2025);
PAINT GREEN (-1550 2025);
DISPLAY INVISIBLE (-1550 2025);
FORCEPROP 1 LAST HDL_TAP TRUE
J 2
(-1875 1950);
DISPLAY 1.234043 (-1875 1950);
PAINT GREEN (-1875 1950);
DISPLAY INVISIBLE (-1875 1950);
FORCEPROP 1 LAST PATH I95
J 2
(-1550 2075);
DISPLAY 0.936170 (-1550 2075);
PAINT GREEN (-1550 2075);
DISPLAY INVISIBLE (-1550 2075);
FORCEADD TAP..6
R 2
(-1550 2025);
FORCEPROP 3 LASTPIN (-1600 2025) SIG_NAME M_F_DQ<15>
J 0
(-1590 2035);
DISPLAY 0.659574 (-1590 2035);
PAINT MONO (-1590 2035);
DISPLAY INVISIBLE (-1590 2035);
FORCEPROP 1 LASTPIN (-1600 2025) BN 15
J 2
(-1550 2035);
DISPLAY 0.617021 (-1550 2035);
PAINT PINK (-1550 2035);
FORCEPROP 2 LAST CDS_LIB mstr_standard
J 2
(-1550 2025);
DISPLAY 0.787234 (-1550 2025);
PAINT MONO (-1550 2025);
DISPLAY INVISIBLE (-1550 2025);
FORCEPROP 1 LAST BODY_TYPE PLUMBING
J 2
(-1550 1975);
DISPLAY 1.234043 (-1550 1975);
PAINT GREEN (-1550 1975);
DISPLAY INVISIBLE (-1550 1975);
FORCEPROP 1 LAST HDL_TAP TRUE
J 2
(-1875 1900);
DISPLAY 1.234043 (-1875 1900);
PAINT GREEN (-1875 1900);
DISPLAY INVISIBLE (-1875 1900);
FORCEPROP 1 LAST PATH I96
J 2
(-1550 2025);
DISPLAY 0.936170 (-1550 2025);
PAINT GREEN (-1550 2025);
DISPLAY INVISIBLE (-1550 2025);
FORCEADD TAP..6
R 2
(-1550 1925);
FORCEPROP 3 LASTPIN (-1600 1925) SIG_NAME M_F_DQ<13>
J 0
(-1590 1935);
DISPLAY 0.659574 (-1590 1935);
PAINT MONO (-1590 1935);
DISPLAY INVISIBLE (-1590 1935);
FORCEPROP 1 LASTPIN (-1600 1925) BN 13
J 2
(-1550 1935);
DISPLAY 0.617021 (-1550 1935);
PAINT PINK (-1550 1935);
FORCEPROP 2 LAST CDS_LIB mstr_standard
J 2
(-1550 1925);
DISPLAY 0.787234 (-1550 1925);
PAINT MONO (-1550 1925);
DISPLAY INVISIBLE (-1550 1925);
FORCEPROP 1 LAST BODY_TYPE PLUMBING
J 2
(-1550 1875);
DISPLAY 1.234043 (-1550 1875);
PAINT GREEN (-1550 1875);
DISPLAY INVISIBLE (-1550 1875);
FORCEPROP 1 LAST HDL_TAP TRUE
J 2
(-1875 1800);
DISPLAY 1.234043 (-1875 1800);
PAINT GREEN (-1875 1800);
DISPLAY INVISIBLE (-1875 1800);
FORCEPROP 1 LAST PATH I97
J 2
(-1550 1925);
DISPLAY 0.936170 (-1550 1925);
PAINT GREEN (-1550 1925);
DISPLAY INVISIBLE (-1550 1925);
FORCEADD TAP..6
R 2
(-1550 1975);
FORCEPROP 3 LASTPIN (-1600 1975) SIG_NAME M_F_DQ<12>
J 0
(-1590 1985);
DISPLAY 0.659574 (-1590 1985);
PAINT MONO (-1590 1985);
DISPLAY INVISIBLE (-1590 1985);
FORCEPROP 1 LASTPIN (-1600 1975) BN 12
J 2
(-1550 1985);
DISPLAY 0.617021 (-1550 1985);
PAINT PINK (-1550 1985);
FORCEPROP 2 LAST CDS_LIB mstr_standard
J 2
(-1550 1975);
DISPLAY 0.787234 (-1550 1975);
PAINT MONO (-1550 1975);
DISPLAY INVISIBLE (-1550 1975);
FORCEPROP 1 LAST BODY_TYPE PLUMBING
J 2
(-1550 1925);
DISPLAY 1.234043 (-1550 1925);
PAINT GREEN (-1550 1925);
DISPLAY INVISIBLE (-1550 1925);
FORCEPROP 1 LAST HDL_TAP TRUE
J 2
(-1875 1850);
DISPLAY 1.234043 (-1875 1850);
PAINT GREEN (-1875 1850);
DISPLAY INVISIBLE (-1875 1850);
FORCEPROP 1 LAST PATH I98
J 2
(-1550 1975);
DISPLAY 0.936170 (-1550 1975);
PAINT GREEN (-1550 1975);
DISPLAY INVISIBLE (-1550 1975);
FORCEADD TAP..6
R 2
(-1550 1875);
FORCEPROP 3 LASTPIN (-1600 1875) SIG_NAME M_F_DQ<10>
J 0
(-1590 1885);
DISPLAY 0.659574 (-1590 1885);
PAINT MONO (-1590 1885);
DISPLAY INVISIBLE (-1590 1885);
FORCEPROP 1 LASTPIN (-1600 1875) BN 10
J 2
(-1550 1885);
DISPLAY 0.617021 (-1550 1885);
PAINT PINK (-1550 1885);
FORCEPROP 2 LAST CDS_LIB mstr_standard
J 2
(-1550 1875);
DISPLAY 0.787234 (-1550 1875);
PAINT MONO (-1550 1875);
DISPLAY INVISIBLE (-1550 1875);
FORCEPROP 1 LAST BODY_TYPE PLUMBING
J 2
(-1550 1825);
DISPLAY 1.234043 (-1550 1825);
PAINT GREEN (-1550 1825);
DISPLAY INVISIBLE (-1550 1825);
FORCEPROP 1 LAST HDL_TAP TRUE
J 2
(-1875 1750);
DISPLAY 1.234043 (-1875 1750);
PAINT GREEN (-1875 1750);
DISPLAY INVISIBLE (-1875 1750);
FORCEPROP 1 LAST PATH I99
J 2
(-1550 1875);
DISPLAY 0.936170 (-1550 1875);
PAINT GREEN (-1550 1875);
DISPLAY INVISIBLE (-1550 1875);
FORCEADD BOM_NOTE..1
(-5075 5275);
FORCEPROP 0 LAST L1 STUFF FOR SKU A & B
J 0
(-5225 5175);
DISPLAY 1.063830 (-5225 5175);
PAINT WHITE (-5225 5175);
FORCEPROP 2 LAST CDS_LIB mstr_symbols
J 0
(-5075 5275);
PAINT ORANGE (-5075 5275);
DISPLAY INVISIBLE (-5075 5275);
FORCEPROP 2 LAST BOM_COST SB
J 0
(-5225 5250);
DISPLAY 1.361702 (-5225 5250);
PAINT ORANGE (-5225 5250);
DISPLAY INVISIBLE (-5225 5250);
FORCEPROP 1 LAST COMMENT_BODY TRUE
J 0
(-5050 5375);
DISPLAY 1.319149 (-5050 5375);
PAINT ORANGE (-5050 5375);
DISPLAY INVISIBLE (-5050 5375);
FORCEPROP 2 LAST ROOM SB_HEADERS
J 0
(-5225 5250);
DISPLAY 1.361702 (-5225 5250);
PAINT ORANGE (-5225 5250);
DISPLAY INVISIBLE (-5225 5250);
FORCEADD INTEL_CORP_BPAGE..1
(2650 500);
FORCEPROP 1 LAST CDS_CON_LAST_MODIFIED Tue Dec 01 11:51:32 2015
J 0
(1225 825);
DISPLAY 0.787234 (1225 825);
PAINT ORANGE (1225 825);
DISPLAY INVISIBLE (1225 825);
FORCEPROP 1 LAST CUSTOM_TXT_CDS <CURRENT_DESIGN_SHEET> OF <TOTAL_DESIGN_SHEETS>
J 0
(2150 525);
PAINT GREEN (2150 525);
FORCEPROP 2 LAST CUSTOM_TXT_CDS <XR_PAGE_TITLE>
J 0
(-5240 5750);
DISPLAY 0.638298 (-5240 5750);
PAINT PINK (-5240 5750);
DISPLAY INVISIBLE (-5240 5750);
FORCEPROP 2 LAST CUSTOM_TXT_CDS <CON_LAST_MODIFIED>
J 0
(1175 850);
DISPLAY 1.042553 (1175 850);
PAINT GREEN (1175 850);
FORCEPROP 1 LAST SCH_ADDRESS3 Santa Clara, CA 95052-8119
J 0
(-1325 525);
DISPLAY 0.617021 (-1325 525);
PAINT GREEN (-1325 525);
FORCEPROP 1 LAST SCH_ADDRESS2 P.O. BOX 58119
J 0
(-1325 575);
DISPLAY 0.617021 (-1325 575);
PAINT GREEN (-1325 575);
FORCEPROP 1 LAST SCH_ADDRESS1 2200 Mission College Blvd.
J 0
(-1325 625);
DISPLAY 0.617021 (-1325 625);
PAINT GREEN (-1325 625);
FORCEPROP 1 LAST SCH_TITLE CPU0 DDR4 CH F DIMM0
J 0
(-5275 550);
DISPLAY 1.212766 (-5275 550);
PAINT WHITE (-5275 550);
FORCEPROP 1 LAST SCH_NUMBER H4694802
J 0
(1350 650);
DISPLAY 1.212766 (1350 650);
PAINT YELLOW (1350 650);
FORCEPROP 1 LAST SCH_DEPT BESD
J 1
(-1800 600);
DISPLAY 1.212766 (-1800 600);
PAINT YELLOW (-1800 600);
FORCEPROP 1 LAST SCH_REV 2.420
J 0
(2400 650);
DISPLAY 0.978723 (2400 650);
PAINT YELLOW (2400 650);
FORCEPROP 2 LAST PAGE_BORDER TRUE
J 0
(-5240 5750);
DISPLAY 0.680851 (-5240 5750);
PAINT PINK (-5240 5750);
DISPLAY INVISIBLE (-5240 5750);
FORCEPROP 2 LAST CDS_LIB mstr_symbols
J 0
(2650 500);
DISPLAY 0.787234 (2650 500);
PAINT MONO (2650 500);
DISPLAY INVISIBLE (2650 500);
FORCEPROP 1 LAST COMMENT_BODY TRUE
J 0
(2660 510);
DISPLAY 0.382979 (2660 510);
PAINT GREEN (2660 510);
DISPLAY INVISIBLE (2660 510);
FORCEPROP 2 LAST CDS_XR_PAGE_TITLE CR-53 : @BASEBOARD_FAB2_LIB.BASEBOARD_FAB2(SCH_1):PAGE53
J 0
(-5240 5750);
DISPLAY 0.638298 (-5240 5750);
PAINT PINK (-5240 5750);
DISPLAY INVISIBLE (-5240 5750);
WIRE 17 -1 (900 5200)(900 5175);
WIRE 17 -1 (1500 5200)(900 5200);
FORCEPROP 2 LAST SIG_NAME M_F_DQS_DN<17:0>
J 0
(925 5210);
DISPLAY 0.617021 (925 5210);
PAINT ORANGE (925 5210);
WIRE 17 -1 (700 5250)(700 5225);
WIRE 17 -1 (1500 5250)(700 5250);
FORCEPROP 2 LAST SIG_NAME M_F_DQS_DP<17:0>
J 0
(925 5260);
DISPLAY 0.617021 (925 5260);
PAINT ORANGE (925 5260);
WIRE 17 -1 (900 4475)(900 4575);
WIRE 17 -1 (900 4375)(900 4475);
WIRE 17 -1 (900 4575)(900 4675);
WIRE 17 -1 (900 4675)(900 4775);
WIRE 17 -1 (900 4275)(900 4375);
WIRE 17 -1 (900 4175)(900 4275);
WIRE 17 -1 (900 4775)(900 4875);
WIRE 17 -1 (900 4875)(900 4975);
WIRE 17 -1 (900 4075)(900 4175);
WIRE 17 -1 (900 3975)(900 4075);
WIRE 17 -1 (900 4975)(900 5075);
WIRE 17 -1 (900 5075)(900 5175);
WIRE 17 -1 (900 3875)(900 3975);
WIRE 17 -1 (900 3775)(900 3875);
WIRE 17 -1 (700 4525)(700 4625);
WIRE 17 -1 (700 4425)(700 4525);
WIRE 17 -1 (700 4625)(700 4725);
WIRE 17 -1 (700 4725)(700 4825);
WIRE 17 -1 (700 4325)(700 4425);
WIRE 17 -1 (700 4225)(700 4325);
WIRE 17 -1 (700 4825)(700 4925);
WIRE 17 -1 (700 4925)(700 5025);
WIRE 17 -1 (700 4125)(700 4225);
WIRE 17 -1 (700 4025)(700 4125);
WIRE 17 -1 (700 5025)(700 5125);
WIRE 17 -1 (700 5125)(700 5225);
WIRE 17 -1 (700 3925)(700 4025);
WIRE 17 -1 (700 3825)(700 3925);
WIRE 17 -1 (700 3725)(700 3825);
WIRE 17 -1 (700 3625)(700 3725);
WIRE 17 -1 (700 3525)(700 3625);
WIRE 17 -1 (900 3675)(900 3775);
WIRE 17 -1 (900 3575)(900 3675);
WIRE 17 -1 (900 3475)(900 3575);
WIRE 17 -1 (-1500 4350)(-1500 4400);
WIRE 17 -1 (-1500 4300)(-1500 4350);
WIRE 17 -1 (-1500 4400)(-1500 4450);
WIRE 17 -1 (-1500 4450)(-1500 4500);
WIRE 17 -1 (-1500 4250)(-1500 4300);
WIRE 17 -1 (-1500 4200)(-1500 4250);
WIRE 17 -1 (-1500 4500)(-1500 4525);
WIRE 17 -1 (-1050 4525)(-1500 4525);
FORCEPROP 2 LAST SIG_NAME M_F_DQ<63:0>
J 0
(-1460 4535);
DISPLAY 0.617021 (-1460 4535);
PAINT ORANGE (-1460 4535);
WIRE 17 -1 (-1500 4150)(-1500 4200);
WIRE 17 -1 (-1500 4100)(-1500 4150);
WIRE 17 -1 (-1500 4050)(-1500 4100);
WIRE 17 -1 (-1500 4000)(-1500 4050);
WIRE 17 -1 (-1500 3950)(-1500 4000);
WIRE 17 -1 (-1500 3900)(-1500 3950);
WIRE 17 -1 (-1500 3850)(-1500 3900);
WIRE 17 -1 (-1500 3800)(-1500 3850);
WIRE 17 -1 (-3100 4250)(-3100 4300);
WIRE 17 -1 (-3100 4200)(-3100 4250);
WIRE 17 -1 (-3100 4300)(-3100 4350);
WIRE 17 -1 (-3100 4350)(-3100 4400);
WIRE 17 -1 (-3100 4150)(-3100 4200);
WIRE 17 -1 (-3100 4100)(-3100 4150);
WIRE 17 -1 (-3100 4400)(-3100 4450);
WIRE 17 -1 (-3100 4450)(-3100 4500);
WIRE 17 -1 (-3100 4050)(-3100 4100);
WIRE 17 -1 (-3100 4000)(-3100 4050);
WIRE 17 -1 (-3100 4500)(-3100 4525);
WIRE 17 -1 (-3650 4525)(-3100 4525);
FORCEPROP 2 LAST SIG_NAME M_F_MA<17:0>
J 0
(-3625 4535);
DISPLAY 0.617021 (-3625 4535);
PAINT ORANGE (-3625 4535);
WIRE 17 -1 (-3100 3950)(-3100 4000);
WIRE 17 -1 (-3100 3900)(-3100 3950);
WIRE 17 -1 (-3100 3850)(-3100 3900);
WIRE 17 -1 (-3100 3800)(-3100 3850);
WIRE 17 -1 (-1500 3750)(-1500 3800);
WIRE 17 -1 (-1500 3700)(-1500 3750);
WIRE 17 -1 (-1500 3650)(-1500 3700);
WIRE 17 -1 (-1500 3600)(-1500 3650);
WIRE 17 -1 (-1500 3550)(-1500 3600);
WIRE 17 -1 (-1500 3500)(-1500 3550);
WIRE 17 -1 (-1500 3450)(-1500 3500);
WIRE 17 -1 (-1500 3400)(-1500 3450);
WIRE 17 -1 (-1500 3350)(-1500 3400);
WIRE 17 -1 (-1500 3300)(-1500 3350);
WIRE 17 -1 (-1500 3250)(-1500 3300);
WIRE 17 -1 (-1500 3200)(-1500 3250);
WIRE 17 -1 (-1500 3150)(-1500 3200);
WIRE 17 -1 (-1500 3100)(-1500 3150);
WIRE 17 -1 (-1500 3050)(-1500 3100);
WIRE 17 -1 (-1500 3000)(-1500 3050);
WIRE 17 -1 (-1500 2950)(-1500 3000);
WIRE 17 -1 (-1500 2900)(-1500 2950);
WIRE 17 -1 (-1500 2850)(-1500 2900);
WIRE 17 -1 (-1500 2800)(-1500 2850);
WIRE 17 -1 (-1500 2750)(-1500 2800);
WIRE 17 -1 (-1500 2700)(-1500 2750);
WIRE 17 -1 (-1500 2650)(-1500 2700);
WIRE 17 -1 (-1500 2600)(-1500 2650);
WIRE 17 -1 (-1500 2550)(-1500 2600);
WIRE 17 -1 (-1500 2500)(-1500 2550);
WIRE 17 -1 (-1500 2450)(-1500 2500);
WIRE 17 -1 (-1500 2400)(-1500 2450);
WIRE 17 -1 (-1500 2350)(-1500 2400);
WIRE 17 -1 (-1500 2300)(-1500 2350);
WIRE 17 -1 (-1500 2250)(-1500 2300);
WIRE 17 -1 (-1500 2200)(-1500 2250);
WIRE 17 -1 (-1500 2150)(-1500 2200);
WIRE 17 -1 (-1500 2100)(-1500 2150);
WIRE 17 -1 (-1500 2050)(-1500 2100);
WIRE 17 -1 (-1500 2000)(-1500 2050);
WIRE 17 -1 (-1500 1950)(-1500 2000);
WIRE 17 -1 (-1500 1900)(-1500 1950);
WIRE 17 -1 (-1500 1850)(-1500 1900);
WIRE 17 -1 (-1500 1800)(-1500 1850);
WIRE 17 -1 (-1500 1750)(-1500 1800);
WIRE 17 -1 (-1500 1700)(-1500 1750);
WIRE 17 -1 (-1500 1650)(-1500 1700);
WIRE 17 -1 (-1500 1600)(-1500 1650);
WIRE 17 -1 (-1500 1550)(-1500 1600);
WIRE 17 -1 (-1500 1500)(-1500 1550);
WIRE 17 -1 (-1500 1450)(-1500 1500);
WIRE 17 -1 (-1500 1400)(-1500 1450);
WIRE 17 -1 (-1500 1350)(-1500 1400);
WIRE 17 -1 (-3100 3650)(-3100 3700);
WIRE 17 -1 (-3100 3700)(-3100 3750);
WIRE 17 -1 (-3100 3750)(-3100 3800);
WIRE 17 -1 (-3100 3575)(-3100 3550);
WIRE 17 -1 (-3100 3575)(-3650 3575);
FORCEPROP 2 LAST SIG_NAME M_F_BA<1:0>
J 0
(-3625 3585);
DISPLAY 0.617021 (-3625 3585);
PAINT ORANGE (-3625 3585);
WIRE 17 -1 (-3100 3200)(-3100 3300);
WIRE 17 -1 (-3100 3325)(-3100 3300);
WIRE 17 -1 (-3100 3325)(-3650 3325);
FORCEPROP 2 LAST SIG_NAME M_F_CLK_DP<3:0>
J 0
(-3625 3335);
DISPLAY 0.617021 (-3625 3335);
PAINT ORANGE (-3625 3335);
WIRE 17 -1 (-3100 3400)(-3100 3450);
WIRE 17 -1 (-3100 3450)(-3650 3450);
FORCEPROP 2 LAST SIG_NAME M_F_BG<1:0>
J 0
(-3625 3460);
DISPLAY 0.617021 (-3625 3460);
PAINT ORANGE (-3625 3460);
WIRE 17 -1 (-3100 3500)(-3100 3550);
WIRE 17 -1 (-3100 3025)(-3100 3000);
WIRE 17 -1 (-3100 3025)(-3650 3025);
FORCEPROP 2 LAST SIG_NAME M_F_CS_N<7:0>
J 0
(-3625 3035);
DISPLAY 0.617021 (-3625 3035);
PAINT ORANGE (-3625 3035);
WIRE 17 -1 (-3100 2950)(-3100 3000);
WIRE 17 -1 (-3100 2900)(-3100 2950);
WIRE 17 -1 (-3100 2850)(-3100 2900);
WIRE 17 -1 (-3100 2775)(-3100 2750);
WIRE 17 -1 (-3100 2775)(-3650 2775);
FORCEPROP 2 LAST SIG_NAME M_F_CKE<3:0>
J 0
(-3625 2785);
DISPLAY 0.617021 (-3625 2785);
PAINT ORANGE (-3625 2785);
WIRE 17 -1 (-3100 2625)(-3100 2600);
WIRE 17 -1 (-3100 2625)(-3650 2625);
FORCEPROP 2 LAST SIG_NAME M_F_ODT<3:0>
J 0
(-3625 2635);
DISPLAY 0.617021 (-3625 2635);
PAINT ORANGE (-3625 2635);
WIRE 17 -1 (-3100 2700)(-3100 2750);
WIRE 17 -1 (-3100 2350)(-3100 2400);
WIRE 17 -1 (-3100 2300)(-3100 2350);
WIRE 17 -1 (-3100 2400)(-3100 2450);
WIRE 17 -1 (-3100 2475)(-3100 2450);
WIRE 17 -1 (-3100 2250)(-3100 2300);
WIRE 17 -1 (-3100 2200)(-3100 2250);
WIRE 17 -1 (-3100 2475)(-3650 2475);
FORCEPROP 2 LAST SIG_NAME M_F_ECC<7:0>
J 0
(-3625 2485);
DISPLAY 0.617021 (-3625 2485);
PAINT ORANGE (-3625 2485);
WIRE 17 -1 (-3100 2150)(-3100 2200);
WIRE 17 -1 (-3100 2100)(-3100 2150);
WIRE 17 -1 (-3100 2550)(-3100 2600);
WIRE 17 -1 (-3300 3275)(-3300 3250);
WIRE 17 -1 (-3300 3275)(-3650 3275);
FORCEPROP 2 LAST SIG_NAME M_F_CLK_DN<3:0>
J 0
(-3625 3285);
DISPLAY 0.617021 (-3625 3285);
PAINT ORANGE (-3625 3285);
WIRE 17 -1 (-3300 3250)(-3300 3150);
WIRE 16 -1 (-950 2550)(-950 2600);
WIRE 16 -1 (-950 2550)(-750 2550);
WIRE 16 -1 (-950 2600)(-750 2600);
WIRE 16 -1 (-1100 2600)(-950 2600);
WIRE 16 -1 (-1100 2700)(-1100 2600);
WIRE 16 -1 (-750 1200)(-900 1200);
WIRE 16 -1 (-900 1250)(-900 1200);
WIRE 16 -1 (-900 1250)(-750 1250);
WIRE 16 -1 (-900 1300)(-900 1250);
WIRE 16 -1 (-900 1300)(-750 1300);
WIRE 16 -1 (-900 1300)(-900 1350);
WIRE 16 -1 (-900 1350)(-750 1350);
WIRE 16 -1 (-900 1350)(-900 1400);
WIRE 16 -1 (-900 1400)(-750 1400);
WIRE 16 -1 (-900 1400)(-900 1450);
WIRE 16 -1 (-900 1450)(-750 1450);
WIRE 16 -1 (-900 1450)(-900 1500);
WIRE 16 -1 (-900 1500)(-900 1550);
WIRE 16 -1 (-900 1500)(-750 1500);
WIRE 16 -1 (-900 1550)(-750 1550);
WIRE 16 -1 (-900 1550)(-900 1600);
WIRE 16 -1 (-900 1600)(-750 1600);
WIRE 16 -1 (-900 1600)(-900 1650);
WIRE 16 -1 (-900 1650)(-750 1650);
WIRE 16 -1 (-900 1650)(-900 1700);
WIRE 16 -1 (-900 1700)(-750 1700);
WIRE 16 -1 (-900 1700)(-900 1750);
WIRE 16 -1 (-900 1750)(-750 1750);
WIRE 16 -1 (-900 1750)(-900 1800);
WIRE 16 -1 (-900 1800)(-750 1800);
WIRE 16 -1 (-900 1800)(-900 1850);
WIRE 16 -1 (-900 1850)(-750 1850);
WIRE 16 -1 (-900 1850)(-900 1900);
WIRE 16 -1 (-900 1900)(-750 1900);
WIRE 16 -1 (-900 1900)(-900 1950);
WIRE 16 -1 (-900 1950)(-750 1950);
WIRE 16 -1 (-900 1950)(-900 2000);
WIRE 16 -1 (-900 2000)(-900 2050);
WIRE 16 -1 (-900 2000)(-750 2000);
WIRE 16 -1 (-900 2050)(-750 2050);
WIRE 16 -1 (-900 2050)(-900 2100);
WIRE 16 -1 (-900 2100)(-750 2100);
WIRE 16 -1 (-900 2100)(-900 2150);
WIRE 16 -1 (-900 2150)(-750 2150);
WIRE 16 -1 (-900 2150)(-900 2200);
WIRE 16 -1 (-900 2200)(-750 2200);
WIRE 16 -1 (-900 2200)(-900 2250);
WIRE 16 -1 (-900 2250)(-750 2250);
WIRE 16 -1 (-900 2250)(-900 2300);
WIRE 16 -1 (-900 2300)(-750 2300);
WIRE 16 -1 (-900 2300)(-900 2350);
WIRE 16 -1 (-900 2350)(-750 2350);
WIRE 16 -1 (-900 2350)(-900 2400);
WIRE 16 -1 (-900 2400)(-750 2400);
WIRE 16 -1 (-900 2400)(-900 2450);
WIRE 16 -1 (-900 2450)(-750 2450);
WIRE 16 -1 (-1275 2450)(-900 2450);
WIRE 16 -1 (-1275 2450)(-1275 2550);
WIRE 16 -1 (2450 3500)(2450 3550);
WIRE 16 -1 (2450 3450)(2450 3500);
WIRE 16 -1 (2450 3500)(2250 3500);
WIRE 16 -1 (2450 3550)(2250 3550);
WIRE 16 -1 (2450 3400)(2450 3450);
WIRE 16 -1 (2450 3450)(2250 3450);
WIRE 16 -1 (2450 3350)(2450 3400);
WIRE 16 -1 (2450 3400)(2250 3400);
WIRE 16 -1 (2450 3300)(2450 3350);
WIRE 16 -1 (2450 3350)(2250 3350);
WIRE 16 -1 (2450 3250)(2450 3300);
WIRE 16 -1 (2450 3300)(2250 3300);
WIRE 16 -1 (2450 3200)(2450 3250);
WIRE 16 -1 (2450 3250)(2250 3250);
WIRE 16 -1 (2450 3150)(2450 3200);
WIRE 16 -1 (2450 3200)(2250 3200);
WIRE 16 -1 (2450 3100)(2450 3150);
WIRE 16 -1 (2450 3150)(2250 3150);
WIRE 16 -1 (2450 3100)(2250 3100);
WIRE 16 -1 (2450 3050)(2450 3100);
WIRE 16 -1 (2450 3000)(2450 3050);
WIRE 16 -1 (2450 3050)(2250 3050);
WIRE 16 -1 (2450 2950)(2450 3000);
WIRE 16 -1 (2450 3000)(2250 3000);
WIRE 16 -1 (2450 2900)(2450 2950);
WIRE 16 -1 (2450 2950)(2250 2950);
WIRE 16 -1 (2450 2850)(2450 2900);
WIRE 16 -1 (2450 2900)(2250 2900);
WIRE 16 -1 (2450 2800)(2450 2850);
WIRE 16 -1 (2450 2850)(2250 2850);
WIRE 16 -1 (2450 2750)(2450 2800);
WIRE 16 -1 (2450 2800)(2250 2800);
WIRE 16 -1 (2450 2700)(2450 2750);
WIRE 16 -1 (2450 2750)(2250 2750);
WIRE 16 -1 (2450 2650)(2450 2700);
WIRE 16 -1 (2450 2700)(2250 2700);
WIRE 16 -1 (2450 2600)(2450 2650);
WIRE 16 -1 (2450 2650)(2250 2650);
WIRE 16 -1 (2450 2600)(2250 2600);
WIRE 16 -1 (2450 2550)(2450 2600);
WIRE 16 -1 (2450 2500)(2450 2550);
WIRE 16 -1 (2450 2550)(2250 2550);
WIRE 16 -1 (2450 2450)(2450 2500);
WIRE 16 -1 (2450 2500)(2250 2500);
WIRE 16 -1 (2450 2400)(2450 2450);
WIRE 16 -1 (2450 2450)(2250 2450);
WIRE 16 -1 (2450 2350)(2450 2400);
WIRE 16 -1 (2450 2400)(2250 2400);
WIRE 16 -1 (2450 2300)(2450 2350);
WIRE 16 -1 (2450 2350)(2250 2350);
WIRE 16 -1 (2450 2250)(2450 2300);
WIRE 16 -1 (2450 2300)(2250 2300);
WIRE 16 -1 (2450 2200)(2450 2250);
WIRE 16 -1 (2450 2250)(2250 2250);
WIRE 16 -1 (2450 2150)(2450 2200);
WIRE 16 -1 (2450 2200)(2250 2200);
WIRE 16 -1 (2450 2100)(2450 2150);
WIRE 16 -1 (2450 2150)(2250 2150);
WIRE 16 -1 (2450 2050)(2450 2100);
WIRE 16 -1 (2450 2100)(2250 2100);
WIRE 16 -1 (2450 2050)(2250 2050);
WIRE 16 -1 (2450 2000)(2450 2050);
WIRE 16 -1 (2450 1950)(2450 2000);
WIRE 16 -1 (2450 2000)(2250 2000);
WIRE 16 -1 (2450 1900)(2450 1950);
WIRE 16 -1 (2450 1950)(2250 1950);
WIRE 16 -1 (2450 1850)(2450 1900);
WIRE 16 -1 (2450 1900)(2250 1900);
WIRE 16 -1 (2450 1800)(2450 1850);
WIRE 16 -1 (2450 1850)(2250 1850);
WIRE 16 -1 (2450 1750)(2450 1800);
WIRE 16 -1 (2450 1800)(2250 1800);
WIRE 16 -1 (2450 1700)(2450 1750);
WIRE 16 -1 (2450 1750)(2250 1750);
WIRE 16 -1 (2450 1650)(2450 1700);
WIRE 16 -1 (2450 1700)(2250 1700);
WIRE 16 -1 (2450 1600)(2450 1650);
WIRE 16 -1 (2450 1650)(2250 1650);
WIRE 16 -1 (2450 1550)(2450 1600);
WIRE 16 -1 (2450 1600)(2250 1600);
WIRE 16 -1 (2450 1550)(2250 1550);
WIRE 16 -1 (2450 1500)(2450 1550);
WIRE 16 -1 (2450 1450)(2450 1500);
WIRE 16 -1 (2450 1500)(2250 1500);
WIRE 16 -1 (2450 1400)(2450 1450);
WIRE 16 -1 (2450 1450)(2250 1450);
WIRE 16 -1 (2450 1350)(2450 1400);
WIRE 16 -1 (2450 1400)(2250 1400);
WIRE 16 -1 (2450 1300)(2450 1350);
WIRE 16 -1 (2450 1350)(2250 1350);
WIRE 16 -1 (2450 1250)(2450 1300);
WIRE 16 -1 (2450 1300)(2250 1300);
WIRE 16 -1 (2450 1150)(2450 1250);
WIRE 16 -1 (2450 1250)(2250 1250);
WIRE 16 -1 (-2800 1525)(-3025 1525);
WIRE 16 -1 (-3025 1525)(-3025 1575);
WIRE 16 -1 (-2800 1575)(-3025 1575);
WIRE 16 -1 (-3025 1575)(-5050 1575);
WIRE 16 -1 (-5050 1525)(-5050 1575);
WIRE 16 -1 (-4500 1025)(-4500 925);
WIRE 16 -1 (-950 2700)(-750 2700);
WIRE 16 -1 (-950 2750)(-950 2700);
WIRE 16 -1 (-950 2750)(-750 2750);
WIRE 16 -1 (-950 2800)(-950 2750);
WIRE 16 -1 (-750 2800)(-950 2800);
WIRE 16 -1 (-950 2850)(-950 2800);
WIRE 16 -1 (-950 2850)(-750 2850);
WIRE 16 -1 (-950 2850)(-950 2900);
WIRE 16 -1 (-950 2900)(-750 2900);
WIRE 16 -1 (-950 3000)(-950 2900);
WIRE 16 -1 (-2800 1625)(-3025 1625);
WIRE 16 -1 (-3025 1625)(-3025 1675);
WIRE 16 -1 (-2800 1675)(-3025 1675);
WIRE 16 -1 (-3025 1675)(-5050 1675);
WIRE 16 -1 (-5050 1775)(-5050 1675);
WIRE 16 -1 (250 2850)(450 2850);
WIRE 16 -1 (450 2850)(450 2900);
WIRE 16 -1 (250 2900)(450 2900);
WIRE 16 -1 (450 3075)(450 2900);
WIRE 16 -1 (1050 3550)(1250 3550);
WIRE 16 -1 (1050 3500)(1050 3550);
WIRE 16 -1 (1050 3500)(1250 3500);
WIRE 16 -1 (1050 3450)(1050 3500);
WIRE 16 -1 (1050 3450)(1250 3450);
WIRE 16 -1 (1050 3400)(1050 3450);
WIRE 16 -1 (1050 3400)(1250 3400);
WIRE 16 -1 (1050 3350)(1050 3400);
WIRE 16 -1 (1050 3350)(1250 3350);
WIRE 16 -1 (1050 3300)(1050 3350);
WIRE 16 -1 (1050 3300)(1250 3300);
WIRE 16 -1 (1050 3250)(1050 3300);
WIRE 16 -1 (1050 3250)(1250 3250);
WIRE 16 -1 (1050 3200)(1050 3250);
WIRE 16 -1 (1050 3200)(1250 3200);
WIRE 16 -1 (1050 3150)(1050 3200);
WIRE 16 -1 (1050 3150)(1250 3150);
WIRE 16 -1 (1050 3100)(1050 3150);
WIRE 16 -1 (1050 3100)(1250 3100);
WIRE 16 -1 (1050 3050)(1050 3100);
WIRE 16 -1 (1050 3050)(1250 3050);
WIRE 16 -1 (1050 3000)(1050 3050);
WIRE 16 -1 (1050 3000)(1250 3000);
WIRE 16 -1 (1050 2950)(1050 3000);
WIRE 16 -1 (1050 2950)(1250 2950);
WIRE 16 -1 (1050 2900)(1050 2950);
WIRE 16 -1 (1050 2900)(1250 2900);
WIRE 16 -1 (1050 2850)(1050 2900);
WIRE 16 -1 (1050 2850)(1250 2850);
WIRE 16 -1 (1050 2800)(1050 2850);
WIRE 16 -1 (1050 2800)(1250 2800);
WIRE 16 -1 (1050 2750)(1050 2800);
WIRE 16 -1 (1050 2750)(1250 2750);
WIRE 16 -1 (1050 2700)(1050 2750);
WIRE 16 -1 (1050 2700)(1250 2700);
WIRE 16 -1 (1050 2650)(1050 2700);
WIRE 16 -1 (1050 2650)(1250 2650);
WIRE 16 -1 (1050 2600)(1050 2650);
WIRE 16 -1 (1050 2600)(1250 2600);
WIRE 16 -1 (1050 2550)(1050 2600);
WIRE 16 -1 (1050 2550)(1250 2550);
WIRE 16 -1 (1050 2500)(1050 2550);
WIRE 16 -1 (1050 2500)(1250 2500);
WIRE 16 -1 (1050 2450)(1050 2500);
WIRE 16 -1 (1050 2450)(1250 2450);
WIRE 16 -1 (1050 2400)(1050 2450);
WIRE 16 -1 (1050 2400)(1250 2400);
WIRE 16 -1 (1050 2350)(1050 2400);
WIRE 16 -1 (1050 2350)(1250 2350);
WIRE 16 -1 (1050 2300)(1050 2350);
WIRE 16 -1 (1050 2300)(1250 2300);
WIRE 16 -1 (1050 2250)(1050 2300);
WIRE 16 -1 (1050 2250)(1250 2250);
WIRE 16 -1 (1050 2200)(1050 2250);
WIRE 16 -1 (1050 2200)(1250 2200);
WIRE 16 -1 (1050 2150)(1050 2200);
WIRE 16 -1 (1050 2150)(1250 2150);
WIRE 16 -1 (1050 2100)(1050 2150);
WIRE 16 -1 (1050 2100)(1250 2100);
WIRE 16 -1 (1050 2050)(1050 2100);
WIRE 16 -1 (1050 2050)(1250 2050);
WIRE 16 -1 (1050 2000)(1050 2050);
WIRE 16 -1 (1050 2000)(1250 2000);
WIRE 16 -1 (1050 1950)(1050 2000);
WIRE 16 -1 (1050 1950)(1250 1950);
WIRE 16 -1 (1050 1900)(1050 1950);
WIRE 16 -1 (1050 1900)(1250 1900);
WIRE 16 -1 (1050 1850)(1050 1900);
WIRE 16 -1 (1050 1850)(1250 1850);
WIRE 16 -1 (1050 1800)(1050 1850);
WIRE 16 -1 (1050 1800)(1250 1800);
WIRE 16 -1 (1050 1750)(1050 1800);
WIRE 16 -1 (1050 1750)(1250 1750);
WIRE 16 -1 (1050 1700)(1050 1750);
WIRE 16 -1 (1050 1700)(1250 1700);
WIRE 16 -1 (1050 1650)(1050 1700);
WIRE 16 -1 (1050 1650)(1250 1650);
WIRE 16 -1 (1050 1600)(1050 1650);
WIRE 16 -1 (1050 1600)(1250 1600);
WIRE 16 -1 (1050 1550)(1050 1600);
WIRE 16 -1 (1050 1550)(1250 1550);
WIRE 16 -1 (1050 1500)(1050 1550);
WIRE 16 -1 (1050 1500)(1250 1500);
WIRE 16 -1 (1050 1450)(1050 1500);
WIRE 16 -1 (1050 1450)(1250 1450);
WIRE 16 -1 (1050 1400)(1050 1450);
WIRE 16 -1 (1050 1400)(1250 1400);
WIRE 16 -1 (1050 1350)(1050 1400);
WIRE 16 -1 (1050 1350)(1250 1350);
WIRE 16 -1 (1050 1300)(1050 1350);
WIRE 16 -1 (1050 1300)(1250 1300);
WIRE 16 -1 (1050 1250)(1050 1300);
WIRE 16 -1 (1050 1250)(1250 1250);
WIRE 16 -1 (1050 1125)(1050 1250);
WIRE 16 -1 (-2800 1325)(-4500 1325);
FORCEPROP 2 LAST SIG_NAME M_F_VREF
J 0
(-3600 1335);
DISPLAY 0.617021 (-3600 1335);
PAINT ORANGE (-3600 1335);
WIRE 16 -1 (-4600 1325)(-4500 1325);
WIRE 16 -1 (-4500 1325)(-4500 1225);
WIRE 16 -1 (-3650 1175)(-2800 1175);
FORCEPROP 2 LAST SIG_NAME TP_CH_F_DIMM_F0_RFU_1
J 0
(-3600 1185);
DISPLAY 0.617021 (-3600 1185);
PAINT ORANGE (-3600 1185);
FORCEPROP 2 LASTPROP $XRERR UNIQUE?
J 0
(-3890 1175);
DISPLAY 0.638298 (-3890 1175);
PAINT MONO (-3890 1175);
DISPLAY INVISIBLE (-3890 1175);
WIRE 16 -1 (-3650 1125)(-2800 1125);
FORCEPROP 2 LAST SIG_NAME TP_CH_F_DIMM_F0_RFU_0
J 0
(-3600 1135);
DISPLAY 0.617021 (-3600 1135);
PAINT ORANGE (-3600 1135);
FORCEPROP 2 LASTPROP $XRERR UNIQUE?
J 0
(-3890 1125);
DISPLAY 0.638298 (-3890 1125);
PAINT MONO (-3890 1125);
DISPLAY INVISIBLE (-3890 1125);
WIRE 16 -1 (-3650 1225)(-2800 1225);
FORCEPROP 2 LAST SIG_NAME TP_CH_F_DIMM_F0_RFU_2
J 0
(-3600 1235);
DISPLAY 0.617021 (-3600 1235);
PAINT ORANGE (-3600 1235);
FORCEPROP 2 LASTPROP $XRERR UNIQUE?
J 0
(-3890 1225);
DISPLAY 0.638298 (-3890 1225);
PAINT MONO (-3890 1225);
DISPLAY INVISIBLE (-3890 1225);
WIRE 16 -1 (-2800 1775)(-3850 1775);
FORCEPROP 2 LAST SIG_NAME M_F_ACT_N
J 0
(-3800 1785);
DISPLAY 0.617021 (-3800 1785);
PAINT ORANGE (-3800 1785);
WIRE 16 -1 (-2800 1825)(-3875 1825);
FORCEPROP 2 LAST SIG_NAME M_F_ALERT_N
J 0
(-3825 1835);
DISPLAY 0.617021 (-3825 1835);
PAINT ORANGE (-3825 1835);
WIRE 16 -1 (-3650 1425)(-2800 1425);
FORCEPROP 2 LAST SIG_NAME SMB_DDR_DEF_VPP_SCL
J 0
(-3610 1435);
DISPLAY 0.617021 (-3610 1435);
PAINT ORANGE (-3610 1435);
WIRE 16 -1 (-3650 1475)(-2800 1475);
FORCEPROP 2 LAST SIG_NAME SMB_DDR_DEF_VPP_SDA
J 0
(-3610 1485);
DISPLAY 0.617021 (-3610 1485);
PAINT ORANGE (-3610 1485);
WIRE 16 -1 (-3650 1025)(-2800 1025);
FORCEPROP 2 LAST SIG_NAME FM_ADR_COMPLETE_DEF_N
J 0
(-3600 1035);
DISPLAY 0.617021 (-3600 1035);
PAINT ORANGE (-3600 1035);
WIRE 16 -1 (-3200 2375)(-3650 2375);
FORCEPROP 2 LAST SIG_NAME M_DEF_RST_N
J 0
(-3625 2385);
DISPLAY 0.617021 (-3625 2385);
PAINT ORANGE (-3625 2385);
WIRE 16 -1 (-3200 1925)(-3200 2375);
WIRE 16 -1 (-2800 1925)(-3200 1925);
WIRE 16 -1 (-3250 2125)(-3975 2125);
FORCEPROP 2 LAST SIG_NAME FM_DIMM_EVENT_COD_N
J 0
(-3937 2139);
DISPLAY 0.617021 (-3937 2139);
PAINT ORANGE (-3937 2139);
WIRE 16 -1 (-3250 1875)(-3250 2125);
WIRE 16 -1 (-3250 1875)(-2800 1875);
WIRE 16 -1 (-3150 2425)(-3650 2425);
FORCEPROP 2 LAST SIG_NAME M_F_PAR
J 0
(-3625 2435);
DISPLAY 0.617021 (-3625 2435);
PAINT ORANGE (-3625 2435);
WIRE 16 -1 (-3150 1975)(-3150 2425);
WIRE 16 -1 (-2800 1975)(-3150 1975);
WIRE 16 -1 (-3200 3125)(-2800 3125);
WIRE 16 -1 (-3200 3225)(-2800 3225);
WIRE 16 -1 (-3000 2525)(-2800 2525);
WIRE 16 -1 (-3000 2425)(-2800 2425);
WIRE 16 -1 (-3000 2075)(-2800 2075);
WIRE 16 -1 (-3000 2125)(-2800 2125);
WIRE 16 -1 (-3000 2175)(-2800 2175);
WIRE 16 -1 (-3000 2225)(-2800 2225);
WIRE 16 -1 (-3000 2275)(-2800 2275);
WIRE 16 -1 (-3000 2325)(-2800 2325);
WIRE 16 -1 (-3000 2375)(-2800 2375);
WIRE 16 -1 (-3000 2825)(-2800 2825);
WIRE 16 -1 (-3000 2675)(-2800 2675);
WIRE 16 -1 (-3000 2575)(-2800 2575);
WIRE 16 -1 (-3000 2725)(-2800 2725);
WIRE 16 -1 (-3000 2875)(-2800 2875);
WIRE 16 -1 (-3000 2925)(-2800 2925);
WIRE 16 -1 (-3000 2975)(-2800 2975);
WIRE 16 -1 (-2800 3025)(-2950 3025);
WIRE 16 -1 (-2950 3025)(-2950 3075);
WIRE 16 -1 (-3650 3075)(-2950 3075);
FORCEPROP 2 LAST SIG_NAME M_F_C<2>
J 0
(-3625 3085);
DISPLAY 0.617021 (-3625 3085);
PAINT ORANGE (-3625 3085);
WIRE 16 -1 (-3000 3475)(-2800 3475);
WIRE 16 -1 (-3000 3425)(-2800 3425);
WIRE 16 -1 (-3000 3375)(-2800 3375);
WIRE 16 -1 (-3000 3275)(-2800 3275);
WIRE 16 -1 (-3000 3175)(-2800 3175);
WIRE 16 -1 (-3000 3525)(-2800 3525);
WIRE 16 -1 (-3000 3725)(-2800 3725);
WIRE 16 -1 (-3000 4075)(-2800 4075);
WIRE 16 -1 (-3000 4025)(-2800 4025);
WIRE 16 -1 (-3000 3975)(-2800 3975);
WIRE 16 -1 (-3000 3925)(-2800 3925);
WIRE 16 -1 (-3000 3875)(-2800 3875);
WIRE 16 -1 (-3000 3825)(-2800 3825);
WIRE 16 -1 (-3000 3775)(-2800 3775);
WIRE 16 -1 (-3000 3675)(-2800 3675);
WIRE 16 -1 (-3000 3625)(-2800 3625);
WIRE 16 -1 (-1600 1525)(-1800 1525);
WIRE 16 -1 (-1600 1475)(-1800 1475);
WIRE 16 -1 (-1600 1425)(-1800 1425);
WIRE 16 -1 (-1600 1325)(-1800 1325);
WIRE 16 -1 (-1600 1375)(-1800 1375);
WIRE 16 -1 (-1600 1575)(-1800 1575);
WIRE 16 -1 (-1600 1625)(-1800 1625);
WIRE 16 -1 (-1600 1675)(-1800 1675);
WIRE 16 -1 (-1600 1725)(-1800 1725);
WIRE 16 -1 (-1600 1775)(-1800 1775);
WIRE 16 -1 (-1600 1875)(-1800 1875);
WIRE 16 -1 (-1600 1975)(-1800 1975);
WIRE 16 -1 (-1600 2025)(-1800 2025);
WIRE 16 -1 (-1600 1825)(-1800 1825);
WIRE 16 -1 (-1600 1925)(-1800 1925);
WIRE 16 -1 (-1600 2175)(-1800 2175);
WIRE 16 -1 (-1600 2075)(-1800 2075);
WIRE 16 -1 (-1600 2125)(-1800 2125);
WIRE 16 -1 (-1600 2375)(-1800 2375);
WIRE 16 -1 (-1600 2425)(-1800 2425);
WIRE 16 -1 (-1600 2475)(-1800 2475);
WIRE 16 -1 (-1600 2225)(-1800 2225);
WIRE 16 -1 (-1600 2275)(-1800 2275);
WIRE 16 -1 (-1600 2325)(-1800 2325);
WIRE 16 -1 (-1600 2525)(-1800 2525);
WIRE 16 -1 (-1600 2625)(-1800 2625);
WIRE 16 -1 (-1600 2675)(-1800 2675);
WIRE 16 -1 (-1600 2575)(-1800 2575);
WIRE 16 -1 (-1600 2825)(-1800 2825);
WIRE 16 -1 (-1600 2875)(-1800 2875);
WIRE 16 -1 (-1600 2925)(-1800 2925);
WIRE 16 -1 (-1600 2975)(-1800 2975);
WIRE 16 -1 (-1600 3025)(-1800 3025);
WIRE 16 -1 (-1600 2725)(-1800 2725);
WIRE 16 -1 (-1600 2775)(-1800 2775);
WIRE 16 -1 (-1600 3225)(-1800 3225);
WIRE 16 -1 (-1600 3125)(-1800 3125);
WIRE 16 -1 (-1600 3075)(-1800 3075);
WIRE 16 -1 (-1600 3175)(-1800 3175);
WIRE 16 -1 (-1600 3275)(-1800 3275);
WIRE 16 -1 (-1600 3325)(-1800 3325);
WIRE 16 -1 (-1600 3375)(-1800 3375);
WIRE 16 -1 (-1600 3425)(-1800 3425);
WIRE 16 -1 (-1600 3475)(-1800 3475);
WIRE 16 -1 (-1600 3525)(-1800 3525);
WIRE 16 -1 (-1600 3575)(-1800 3575);
WIRE 16 -1 (-1600 3675)(-1800 3675);
WIRE 16 -1 (-1600 3725)(-1800 3725);
WIRE 16 -1 (-1600 3775)(-1800 3775);
WIRE 16 -1 (-1600 3825)(-1800 3825);
WIRE 16 -1 (-1600 3875)(-1800 3875);
WIRE 16 -1 (-1600 3925)(-1800 3925);
WIRE 16 -1 (-1600 3975)(-1800 3975);
WIRE 16 -1 (-1600 4025)(-1800 4025);
WIRE 16 -1 (-1600 3625)(-1800 3625);
WIRE 16 -1 (-1600 4075)(-1800 4075);
WIRE 16 -1 (-3000 4425)(-2800 4425);
WIRE 16 -1 (-3000 4375)(-2800 4375);
WIRE 16 -1 (-3000 4325)(-2800 4325);
WIRE 16 -1 (-3000 4175)(-2800 4175);
WIRE 16 -1 (-3000 4125)(-2800 4125);
WIRE 16 -1 (-3000 4475)(-2800 4475);
WIRE 16 -1 (-3000 4275)(-2800 4275);
WIRE 16 -1 (-3000 4225)(-2800 4225);
WIRE 16 -1 (-1600 4475)(-1800 4475);
WIRE 16 -1 (-1600 4425)(-1800 4425);
WIRE 16 -1 (-1600 4375)(-1800 4375);
WIRE 16 -1 (-1600 4225)(-1800 4225);
WIRE 16 -1 (-1600 4175)(-1800 4175);
WIRE 16 -1 (-1600 4125)(-1800 4125);
WIRE 16 -1 (-1600 4275)(-1800 4275);
WIRE 16 -1 (-1600 4325)(-1800 4325);
WIRE 16 -1 (800 4050)(400 4050);
WIRE 16 -1 (600 4000)(400 4000);
WIRE 16 -1 (800 3950)(400 3950);
WIRE 16 -1 (600 3900)(400 3900);
WIRE 16 -1 (800 3850)(400 3850);
WIRE 16 -1 (600 3800)(400 3800);
WIRE 16 -1 (800 3750)(400 3750);
WIRE 16 -1 (600 3700)(400 3700);
WIRE 16 -1 (800 3650)(400 3650);
WIRE 16 -1 (600 3600)(400 3600);
WIRE 16 -1 (800 3550)(400 3550);
WIRE 16 -1 (600 3500)(400 3500);
WIRE 16 -1 (800 3450)(400 3450);
WIRE 16 -1 (600 4400)(400 4400);
WIRE 16 -1 (800 4350)(400 4350);
WIRE 16 -1 (600 4300)(400 4300);
WIRE 16 -1 (800 4250)(400 4250);
WIRE 16 -1 (600 4200)(400 4200);
WIRE 16 -1 (800 4150)(400 4150);
WIRE 16 -1 (600 4100)(400 4100);
WIRE 16 -1 (600 5100)(400 5100);
WIRE 16 -1 (800 5050)(400 5050);
WIRE 16 -1 (600 5000)(400 5000);
WIRE 16 -1 (800 4950)(400 4950);
WIRE 16 -1 (600 4900)(400 4900);
WIRE 16 -1 (800 4850)(400 4850);
WIRE 16 -1 (600 4800)(400 4800);
WIRE 16 -1 (800 4750)(400 4750);
WIRE 16 -1 (600 4700)(400 4700);
WIRE 16 -1 (800 4650)(400 4650);
WIRE 16 -1 (600 4600)(400 4600);
WIRE 16 -1 (800 4550)(400 4550);
WIRE 16 -1 (600 4500)(400 4500);
WIRE 16 -1 (800 4450)(400 4450);
WIRE 16 -1 (600 5200)(400 5200);
WIRE 16 -1 (800 5150)(400 5150);
DOT 1 (-3025 1575);
DOT 1 (-3025 1675);
DOT 1 (-950 2850);
DOT 1 (-950 2800);
DOT 1 (-950 2750);
DOT 1 (1050 2250);
DOT 1 (2450 3500);
DOT 1 (1050 3500);
DOT 1 (2450 3450);
DOT 1 (2450 3400);
DOT 1 (2450 3350);
DOT 1 (2450 3300);
DOT 1 (2450 3250);
DOT 1 (2450 3200);
DOT 1 (2450 3150);
DOT 1 (2450 3100);
DOT 1 (2450 3000);
DOT 1 (2450 3050);
DOT 1 (2450 2950);
DOT 1 (2450 2900);
DOT 1 (2450 2850);
DOT 1 (2450 2800);
DOT 1 (2450 2750);
DOT 1 (2450 2700);
DOT 1 (2450 2650);
DOT 1 (2450 2600);
DOT 1 (2450 2550);
DOT 1 (2450 2500);
DOT 1 (2450 2400);
DOT 1 (2450 2450);
DOT 1 (2450 2350);
DOT 1 (2450 2300);
DOT 1 (2450 2250);
DOT 1 (2450 2150);
DOT 1 (2450 2200);
DOT 1 (2450 2100);
DOT 1 (2450 2050);
DOT 1 (2450 1950);
DOT 1 (2450 1850);
DOT 1 (2450 1900);
DOT 1 (2450 1800);
DOT 1 (2450 1750);
DOT 1 (2450 1600);
DOT 1 (2450 1700);
DOT 1 (2450 1650);
DOT 1 (2450 1550);
DOT 1 (2450 1500);
DOT 1 (2450 1450);
DOT 1 (2450 1400);
DOT 1 (2450 1350);
DOT 1 (2450 1300);
DOT 1 (2450 1250);
DOT 1 (1050 3400);
DOT 1 (1050 3450);
DOT 1 (1050 3350);
DOT 1 (1050 3300);
DOT 1 (1050 3250);
DOT 1 (1050 3150);
DOT 1 (1050 3200);
DOT 1 (1050 3000);
DOT 1 (1050 3050);
DOT 1 (1050 3100);
DOT 1 (1050 2900);
DOT 1 (1050 2950);
DOT 1 (1050 2850);
DOT 1 (1050 2800);
DOT 1 (1050 2750);
DOT 1 (1050 2650);
DOT 1 (1050 2700);
DOT 1 (1050 2500);
DOT 1 (1050 2550);
DOT 1 (1050 2600);
DOT 1 (1050 2450);
DOT 1 (1050 2400);
DOT 1 (1050 2350);
DOT 1 (1050 2300);
DOT 1 (1050 2200);
DOT 1 (1050 2150);
DOT 1 (1050 2100);
DOT 1 (1050 2000);
DOT 1 (1050 2050);
DOT 1 (1050 1950);
DOT 1 (1050 1900);
DOT 1 (1050 1850);
DOT 1 (1050 1750);
DOT 1 (1050 1800);
DOT 1 (1050 1700);
DOT 1 (1050 1650);
DOT 1 (1050 1600);
DOT 1 (1050 1550);
DOT 1 (1050 1500);
DOT 1 (1050 1450);
DOT 1 (1050 1350);
DOT 1 (1050 1400);
DOT 1 (1050 1250);
DOT 1 (1050 1300);
DOT 1 (-950 2900);
DOT 1 (-900 2350);
DOT 1 (-900 2400);
DOT 1 (-900 2450);
DOT 1 (-900 2300);
DOT 1 (-900 2250);
DOT 1 (-950 2600);
DOT 1 (-900 2200);
DOT 1 (-900 2150);
DOT 1 (-900 1950);
DOT 1 (-900 1900);
DOT 1 (-900 1850);
DOT 1 (-900 1750);
DOT 1 (-900 1700);
DOT 1 (-900 1650);
DOT 1 (-900 1600);
DOT 1 (-900 1550);
DOT 1 (-900 1500);
DOT 1 (-900 1450);
DOT 1 (-900 1350);
DOT 1 (-900 1400);
DOT 1 (-900 1250);
DOT 1 (-900 1300);
DOT 1 (-900 1800);
DOT 1 (-900 2000);
DOT 1 (-900 2050);
DOT 1 (-900 2100);
DOT 1 (-4500 1325);
DOT 1 (2450 2000);
DOT 1 (450 2900);
FORCENOTE
PLACE CAP NEAR DIMM CONNECTOR
(-4388 877) 0;
DISPLAY LEFT (-4388 877);
DISPLAY 1.021277 (-4388 877);
PAINT PURPLE (-4388 877);
FORCENOTE
SMBUS ADDR: 0XA8
(-5300 734) 0;
DISPLAY LEFT (-5300 734);
DISPLAY 1.574468 (-5300 734);
PAINT PURPLE (-5300 734);
QUIT
